G04*
G04 #@! TF.GenerationSoftware,Altium Limited,Altium Designer,23.7.1 (13)*
G04*
G04 Layer_Physical_Order=4*
G04 Layer_Color=6736896*
%FSLAX25Y25*%
%MOIN*%
G70*
G04*
G04 #@! TF.SameCoordinates,AF00DCEB-AC48-4C7C-91EA-99F42E284231*
G04*
G04*
G04 #@! TF.FilePolarity,Positive*
G04*
G01*
G75*
%ADD11C,0.02000*%
%ADD16C,0.00500*%
%ADD17C,0.01500*%
%ADD18C,0.01000*%
%ADD25C,0.00800*%
%ADD249C,0.05906*%
%ADD250C,0.01600*%
%ADD252C,0.00500*%
G36*
X519291Y-5118D02*
X530315D01*
Y-15354D01*
X551504D01*
X552078Y-15469D01*
X553341D01*
X553915Y-15354D01*
X573204D01*
X573778Y-15469D01*
X575041D01*
X575615Y-15354D01*
X623622D01*
Y-29874D01*
X623390Y-29970D01*
X622884Y-30476D01*
X622610Y-31138D01*
Y-31854D01*
X622884Y-32516D01*
X623390Y-33022D01*
X623622Y-33118D01*
Y-38976D01*
X624016D01*
Y-55512D01*
X623622Y-55905D01*
Y-74067D01*
X583413D01*
X570079Y-87402D01*
Y-90158D01*
X553543Y-106693D01*
X548501D01*
X547626Y-104974D01*
X546349Y-103218D01*
X544814Y-101682D01*
X543057Y-100406D01*
X541122Y-99420D01*
X539057Y-98749D01*
X536912Y-98409D01*
X534741D01*
X532596Y-98749D01*
X530531Y-99420D01*
X528596Y-100406D01*
X526840Y-101682D01*
X525304Y-103218D01*
X524028Y-104974D01*
X523042Y-106909D01*
X522371Y-108974D01*
X522031Y-111119D01*
Y-113290D01*
X522316Y-115086D01*
X501378Y-136024D01*
X438378D01*
Y-125402D01*
X446457Y-117323D01*
X452732Y-111047D01*
X486590D01*
X512992Y-84646D01*
X542520D01*
X553098Y-74067D01*
X545778D01*
Y-42764D01*
X545894Y-42484D01*
Y-41768D01*
X545778Y-41488D01*
Y-34646D01*
X486221D01*
Y-25281D01*
X426520D01*
X425889Y-25181D01*
X423717D01*
X423086Y-25281D01*
X355752D01*
X355121Y-25181D01*
X352950D01*
X352318Y-25281D01*
X340158D01*
Y-48819D01*
X309842D01*
Y-2756D01*
X362489D01*
X363005Y-2924D01*
X364715Y-3195D01*
X366446D01*
X368157Y-2924D01*
X368673Y-2756D01*
X519291D01*
Y-5118D01*
D02*
G37*
G36*
X179134Y-46260D02*
X252234D01*
X292520Y-85725D01*
Y-147244D01*
X266535D01*
X263386Y-144095D01*
Y-109487D01*
X263743Y-109339D01*
X264250Y-108832D01*
X264524Y-108171D01*
Y-107455D01*
X264250Y-106793D01*
X263743Y-106287D01*
X263082Y-106013D01*
X262706D01*
X257087Y-100394D01*
X231550D01*
Y-91339D01*
X213779D01*
Y-100394D01*
X205695D01*
X205350Y-100049D01*
X204689Y-99775D01*
X203973D01*
X203311Y-100049D01*
X202966Y-100394D01*
X192126D01*
X192026Y-100494D01*
X191511Y-100302D01*
X191290Y-99768D01*
X190783Y-99261D01*
X190122Y-98987D01*
X189406D01*
X188744Y-99261D01*
X188238Y-99768D01*
X187964Y-100429D01*
Y-101145D01*
X188238Y-101807D01*
X188744Y-102313D01*
X189278Y-102534D01*
X189470Y-103049D01*
X185827Y-106693D01*
X169314D01*
X168773Y-106152D01*
X168891Y-105562D01*
X169130Y-105463D01*
X169636Y-104957D01*
X169910Y-104295D01*
Y-103579D01*
X169636Y-102917D01*
X169130Y-102411D01*
X168468Y-102137D01*
X167752D01*
X167091Y-102411D01*
X166584Y-102917D01*
X166485Y-103157D01*
X165895Y-103274D01*
X162716Y-100095D01*
Y-96522D01*
X162943Y-96295D01*
X163217Y-95634D01*
Y-94918D01*
X162943Y-94256D01*
X162716Y-94029D01*
Y-90194D01*
X162754Y-90158D01*
X180709D01*
X181485Y-89381D01*
X181630Y-89321D01*
X182136Y-88815D01*
X182196Y-88670D01*
X183858Y-87008D01*
Y-83465D01*
X158500D01*
Y-77953D01*
X158422Y-77563D01*
X158201Y-77232D01*
X157870Y-77011D01*
X157480Y-76933D01*
X140551D01*
X140161Y-77011D01*
X139830Y-77232D01*
X137862Y-79200D01*
X137733Y-79393D01*
X137233Y-79241D01*
Y-78776D01*
X136959Y-78114D01*
X136453Y-77608D01*
X135791Y-77334D01*
X135075D01*
X134413Y-77608D01*
X133907Y-78114D01*
X133633Y-78776D01*
Y-79492D01*
X133907Y-80154D01*
X134413Y-80660D01*
X135075Y-80934D01*
X135791D01*
X136453Y-80660D01*
X136959Y-80154D01*
X137080Y-79861D01*
X137563Y-79921D01*
Y-83465D01*
X79134D01*
Y-54331D01*
Y-37795D01*
X117209D01*
X117752Y-38021D01*
X118468D01*
X119012Y-37795D01*
X166704D01*
Y-38153D01*
X166978Y-38815D01*
X167484Y-39321D01*
X168146Y-39595D01*
X168862D01*
X169524Y-39321D01*
X170030Y-38815D01*
X170304Y-38153D01*
Y-37795D01*
X179134D01*
Y-46260D01*
D02*
G37*
G36*
X492520Y-72835D02*
X479921D01*
X478083Y-74850D01*
X477988Y-74852D01*
X477326Y-74578D01*
X476611D01*
X475949Y-74852D01*
X475443Y-75358D01*
X475169Y-76020D01*
Y-76736D01*
X475443Y-77398D01*
X475607Y-77562D01*
X462487Y-91943D01*
X461903Y-91841D01*
X461762Y-91500D01*
X461256Y-90994D01*
X460594Y-90720D01*
X459878D01*
X459217Y-90994D01*
X458710Y-91500D01*
X458436Y-92162D01*
Y-92878D01*
X458710Y-93539D01*
X459217Y-94046D01*
X459706Y-94248D01*
X459897Y-94782D01*
X435039Y-122025D01*
Y-139370D01*
X523228D01*
Y-148425D01*
X568504D01*
Y-207087D01*
X469291D01*
Y-170079D01*
X429339D01*
X428461Y-169200D01*
X428578Y-168610D01*
X428863Y-168492D01*
X429369Y-167986D01*
X429643Y-167324D01*
Y-166608D01*
X429369Y-165947D01*
X428863Y-165440D01*
X428201Y-165166D01*
X427502D01*
X427422Y-164764D01*
X427112Y-164301D01*
X427112Y-164301D01*
X424676Y-161864D01*
X424213Y-161555D01*
X423666Y-161446D01*
X423666Y-161446D01*
X420706D01*
X416726Y-157466D01*
X416263Y-157156D01*
X415717Y-157048D01*
X415717Y-157048D01*
X409094D01*
X406609Y-154563D01*
X395353Y-143307D01*
X375577Y-143307D01*
X372047Y-139777D01*
Y-126772D01*
X357530D01*
X355906Y-125147D01*
Y-108004D01*
X355906Y-107874D01*
X356013Y-107419D01*
X356054Y-107402D01*
X356561Y-106895D01*
X356835Y-106234D01*
Y-105518D01*
X356561Y-104856D01*
X356054Y-104350D01*
X355393Y-104076D01*
X354677D01*
X354015Y-104350D01*
X353509Y-104856D01*
X353235Y-105518D01*
Y-106234D01*
X353509Y-106895D01*
X353988Y-107374D01*
X353977Y-107510D01*
X353849Y-107874D01*
X347244D01*
Y-61024D01*
X427003D01*
Y-52595D01*
X428034Y-52432D01*
X430099Y-51761D01*
X432033Y-50775D01*
X433790Y-49499D01*
X435326Y-47963D01*
X436602Y-46207D01*
X437588Y-44272D01*
X438259Y-42207D01*
X438598Y-40062D01*
Y-37891D01*
X438394Y-36601D01*
X438719Y-36220D01*
X492520D01*
Y-72835D01*
D02*
G37*
G36*
X157480Y-91368D02*
X157343Y-91574D01*
X157234Y-92120D01*
X157234Y-92120D01*
Y-94356D01*
X153643Y-97947D01*
X153508Y-97891D01*
X152792D01*
X152130Y-98165D01*
X151624Y-98671D01*
X151350Y-99333D01*
Y-100049D01*
X151406Y-100184D01*
X149803Y-101786D01*
Y-102515D01*
X149303Y-102751D01*
X148783Y-102536D01*
X148067D01*
X147406Y-102810D01*
X146899Y-103316D01*
X146625Y-103978D01*
Y-104694D01*
X146899Y-105355D01*
X147406Y-105862D01*
X148067Y-106136D01*
X148783D01*
X149303Y-105920D01*
X149803Y-106157D01*
Y-118112D01*
X149213Y-118356D01*
X148707Y-118862D01*
X148433Y-119524D01*
Y-120240D01*
X148707Y-120902D01*
X149213Y-121408D01*
X149666Y-121596D01*
X149728Y-122114D01*
X149337Y-122505D01*
X148915Y-122680D01*
X148409Y-123186D01*
X148234Y-123608D01*
X141014Y-130828D01*
X140428Y-130585D01*
X139712D01*
X139050Y-130859D01*
X138544Y-131366D01*
X138270Y-132027D01*
Y-132743D01*
X138342Y-132919D01*
X138008Y-133419D01*
X129340D01*
X126378Y-130456D01*
Y-113764D01*
X138583Y-101559D01*
Y-79921D01*
X140551Y-77953D01*
X157480D01*
Y-91368D01*
D02*
G37*
G36*
X477559Y-231102D02*
X459414D01*
X459208Y-230965D01*
X458661Y-230856D01*
X458661Y-230856D01*
X444488D01*
Y-226804D01*
X444988Y-226510D01*
X445410Y-226684D01*
X446126D01*
X446788Y-226411D01*
X447294Y-225904D01*
X447568Y-225243D01*
Y-224527D01*
X447294Y-223865D01*
X446788Y-223359D01*
X446126Y-223084D01*
X445410D01*
X444748Y-223359D01*
X444242Y-223865D01*
X443968Y-224527D01*
Y-225243D01*
X444068Y-225484D01*
X443734Y-225984D01*
X429184D01*
X428346Y-225147D01*
Y-215011D01*
X433121Y-210236D01*
X477559D01*
Y-231102D01*
D02*
G37*
%LPC*%
G36*
X601539Y-21822D02*
X600823D01*
X600162Y-22096D01*
X599655Y-22602D01*
X599483Y-23018D01*
X598942D01*
X598770Y-22602D01*
X598264Y-22096D01*
X597602Y-21822D01*
X596886D01*
X596224Y-22096D01*
X595718Y-22602D01*
X595444Y-23264D01*
Y-23980D01*
X595718Y-24642D01*
X595947Y-24870D01*
X596188Y-25197D01*
X595947Y-25523D01*
X595718Y-25752D01*
X595444Y-26414D01*
Y-27130D01*
X595718Y-27791D01*
X595947Y-28020D01*
X596188Y-28346D01*
X595947Y-28673D01*
X595718Y-28902D01*
X595444Y-29563D01*
Y-30279D01*
X595718Y-30941D01*
X596224Y-31447D01*
X596886Y-31721D01*
X597602D01*
X598264Y-31447D01*
X598770Y-30941D01*
X598942Y-30526D01*
X599483D01*
X599655Y-30941D01*
X600162Y-31447D01*
X600823Y-31721D01*
X601539D01*
X602201Y-31447D01*
X602707Y-30941D01*
X602981Y-30279D01*
Y-29563D01*
X602707Y-28902D01*
X602479Y-28673D01*
X602237Y-28346D01*
X602479Y-28020D01*
X602707Y-27791D01*
X602981Y-27130D01*
Y-26414D01*
X602707Y-25752D01*
X602479Y-25523D01*
X602237Y-25197D01*
X602479Y-24870D01*
X602707Y-24642D01*
X602981Y-23980D01*
Y-23264D01*
X602707Y-22602D01*
X602201Y-22096D01*
X601539Y-21822D01*
D02*
G37*
G36*
X616106Y-30483D02*
X615390D01*
X614728Y-30757D01*
X614222Y-31264D01*
X613948Y-31925D01*
Y-32642D01*
X614222Y-33303D01*
X614728Y-33809D01*
X615390Y-34084D01*
X616106D01*
X616768Y-33809D01*
X617274Y-33303D01*
X617548Y-32642D01*
Y-31925D01*
X617274Y-31264D01*
X616768Y-30757D01*
X616106Y-30483D01*
D02*
G37*
G36*
X611775Y-31271D02*
X611059D01*
X610398Y-31545D01*
X609891Y-32051D01*
X609617Y-32713D01*
Y-33429D01*
X609891Y-34091D01*
X610398Y-34597D01*
X611059Y-34871D01*
X611775D01*
X612437Y-34597D01*
X612943Y-34091D01*
X613217Y-33429D01*
Y-32713D01*
X612943Y-32051D01*
X612437Y-31545D01*
X611775Y-31271D01*
D02*
G37*
G36*
X620437Y-30090D02*
X619721D01*
X619059Y-30364D01*
X618553Y-30870D01*
X618279Y-31532D01*
Y-32248D01*
X618553Y-32909D01*
X619059Y-33416D01*
X619721Y-33690D01*
X620015D01*
X620115Y-34190D01*
X619846Y-34301D01*
X619340Y-34807D01*
X619066Y-35469D01*
Y-36185D01*
X619340Y-36846D01*
X619846Y-37353D01*
X620508Y-37627D01*
X621224D01*
X621886Y-37353D01*
X622392Y-36846D01*
X622666Y-36185D01*
Y-35469D01*
X622392Y-34807D01*
X621886Y-34301D01*
X621224Y-34027D01*
X620930D01*
X620830Y-33527D01*
X621098Y-33416D01*
X621605Y-32909D01*
X621879Y-32248D01*
Y-31532D01*
X621605Y-30870D01*
X621098Y-30364D01*
X620437Y-30090D01*
D02*
G37*
G36*
X612169Y-36389D02*
X611453D01*
X610791Y-36663D01*
X610285Y-37169D01*
X610011Y-37831D01*
Y-38547D01*
X610285Y-39209D01*
X610791Y-39715D01*
X611453Y-39989D01*
X612169D01*
X612831Y-39715D01*
X613337Y-39209D01*
X613433Y-38976D01*
X613611Y-38547D01*
Y-37831D01*
X613337Y-37169D01*
X612831Y-36663D01*
X612169Y-36389D01*
D02*
G37*
G36*
X618468Y-60405D02*
X617752D01*
X617091Y-60679D01*
X616584Y-61185D01*
X616310Y-61847D01*
Y-62563D01*
X616584Y-63224D01*
X617091Y-63731D01*
X617752Y-64005D01*
X618468D01*
X619130Y-63731D01*
X619636Y-63224D01*
X619910Y-62563D01*
Y-61847D01*
X619636Y-61185D01*
X619130Y-60679D01*
X618468Y-60405D01*
D02*
G37*
G36*
X608764Y-68279D02*
X608047D01*
X607386Y-68553D01*
X606880Y-69059D01*
X606605Y-69721D01*
Y-70437D01*
X606880Y-71098D01*
X607386Y-71605D01*
X608047Y-71879D01*
X608764D01*
X609425Y-71605D01*
X609932Y-71098D01*
X610206Y-70437D01*
Y-69721D01*
X609932Y-69059D01*
X609425Y-68553D01*
X608764Y-68279D01*
D02*
G37*
G36*
X465319Y-123397D02*
X464603D01*
X463941Y-123671D01*
X463435Y-124177D01*
X463161Y-124839D01*
Y-125555D01*
X463435Y-126216D01*
X463941Y-126723D01*
X464603Y-126997D01*
X465319D01*
X465980Y-126723D01*
X466487Y-126216D01*
X466761Y-125555D01*
Y-124839D01*
X466487Y-124177D01*
X465980Y-123671D01*
X465319Y-123397D01*
D02*
G37*
G36*
X157445Y-39932D02*
X156729D01*
X156067Y-40206D01*
X155561Y-40713D01*
X155287Y-41374D01*
Y-42090D01*
X155561Y-42752D01*
X156067Y-43258D01*
X156729Y-43532D01*
X157445D01*
X158106Y-43258D01*
X158613Y-42752D01*
X158887Y-42090D01*
Y-41374D01*
X158613Y-40713D01*
X158106Y-40206D01*
X157445Y-39932D01*
D02*
G37*
G36*
X169256Y-42294D02*
X168540D01*
X167878Y-42568D01*
X167372Y-43075D01*
X167098Y-43736D01*
Y-44453D01*
X167372Y-45114D01*
X167878Y-45620D01*
X168540Y-45895D01*
X169256D01*
X169917Y-45620D01*
X170424Y-45114D01*
X170698Y-44453D01*
Y-43736D01*
X170424Y-43075D01*
X169917Y-42568D01*
X169256Y-42294D01*
D02*
G37*
G36*
X118075Y-45493D02*
X117359D01*
X116697Y-45767D01*
X116191Y-46273D01*
X115917Y-46935D01*
Y-47651D01*
X116191Y-48313D01*
X116697Y-48819D01*
X117359Y-49093D01*
X118075D01*
X118736Y-48819D01*
X119243Y-48313D01*
X119517Y-47651D01*
Y-46935D01*
X119243Y-46273D01*
X118736Y-45767D01*
X118075Y-45493D01*
D02*
G37*
G36*
X169256Y-47806D02*
X168540D01*
X167878Y-48080D01*
X167372Y-48587D01*
X167098Y-49248D01*
Y-49964D01*
X167372Y-50626D01*
X167878Y-51132D01*
X168540Y-51406D01*
X169256D01*
X169917Y-51132D01*
X170424Y-50626D01*
X170698Y-49964D01*
Y-49248D01*
X170424Y-48587D01*
X169917Y-48080D01*
X169256Y-47806D01*
D02*
G37*
G36*
X153114D02*
X152398D01*
X151736Y-48080D01*
X151230Y-48587D01*
X150956Y-49248D01*
Y-49964D01*
X151230Y-50626D01*
X151736Y-51132D01*
X152398Y-51406D01*
X153114D01*
X153776Y-51132D01*
X154282Y-50626D01*
X154556Y-49964D01*
Y-49248D01*
X154282Y-48587D01*
X153776Y-48080D01*
X153114Y-47806D01*
D02*
G37*
G36*
X122012Y-50956D02*
X121295D01*
X120634Y-51230D01*
X120128Y-51736D01*
X119853Y-52398D01*
Y-53114D01*
X120128Y-53776D01*
X120634Y-54282D01*
X121295Y-54556D01*
X122012D01*
X122673Y-54282D01*
X123179Y-53776D01*
X123453Y-53114D01*
Y-52398D01*
X123179Y-51736D01*
X122673Y-51230D01*
X122012Y-50956D01*
D02*
G37*
G36*
X210988Y-51350D02*
X210272D01*
X209610Y-51624D01*
X209104Y-52130D01*
X208830Y-52792D01*
Y-53508D01*
X209104Y-54169D01*
X209610Y-54676D01*
X210272Y-54950D01*
X210988D01*
X211649Y-54676D01*
X212156Y-54169D01*
X212430Y-53508D01*
Y-52792D01*
X212156Y-52130D01*
X211649Y-51624D01*
X210988Y-51350D01*
D02*
G37*
G36*
X138794Y-51096D02*
X137801D01*
X136883Y-51476D01*
X136181Y-52178D01*
X135801Y-53096D01*
Y-54089D01*
X136181Y-55006D01*
X136883Y-55708D01*
X137801Y-56088D01*
X138794D01*
X139711Y-55708D01*
X140413Y-55006D01*
X140793Y-54089D01*
Y-53096D01*
X140413Y-52178D01*
X139711Y-51476D01*
X138794Y-51096D01*
D02*
G37*
G36*
X153114Y-55680D02*
X152398D01*
X151736Y-55954D01*
X151230Y-56461D01*
X150956Y-57122D01*
Y-57838D01*
X151230Y-58500D01*
X151736Y-59006D01*
X152398Y-59280D01*
X153114D01*
X153776Y-59006D01*
X154282Y-58500D01*
X154556Y-57838D01*
Y-57122D01*
X154282Y-56461D01*
X153776Y-55954D01*
X153114Y-55680D01*
D02*
G37*
G36*
X121815Y-55729D02*
X121099D01*
X120437Y-56003D01*
X119931Y-56510D01*
X119657Y-57171D01*
Y-57887D01*
X119931Y-58549D01*
X120437Y-59055D01*
X121099Y-59329D01*
X121815D01*
X122476Y-59055D01*
X122983Y-58549D01*
X123257Y-57887D01*
Y-57171D01*
X122983Y-56510D01*
X122476Y-56003D01*
X121815Y-55729D01*
D02*
G37*
G36*
X209899Y-56889D02*
X209183D01*
X208522Y-57163D01*
X208015Y-57670D01*
X207741Y-58331D01*
Y-59047D01*
X208015Y-59709D01*
X208522Y-60215D01*
X209183Y-60489D01*
X209899D01*
X210561Y-60215D01*
X211067Y-59709D01*
X211341Y-59047D01*
Y-58331D01*
X211067Y-57670D01*
X210561Y-57163D01*
X209899Y-56889D01*
D02*
G37*
G36*
X108232Y-58043D02*
X107516D01*
X106854Y-58317D01*
X106348Y-58823D01*
X106074Y-59484D01*
Y-60201D01*
X106348Y-60862D01*
X106854Y-61369D01*
X107270Y-61540D01*
Y-62082D01*
X106854Y-62254D01*
X106348Y-62760D01*
X106074Y-63421D01*
Y-64138D01*
X106348Y-64799D01*
X106854Y-65306D01*
X107516Y-65579D01*
X108232D01*
X108894Y-65306D01*
X109400Y-64799D01*
X109674Y-64138D01*
Y-63421D01*
X109400Y-62760D01*
X108894Y-62254D01*
X108478Y-62082D01*
Y-61540D01*
X108894Y-61369D01*
X109400Y-60862D01*
X109674Y-60201D01*
Y-59484D01*
X109400Y-58823D01*
X108894Y-58317D01*
X108232Y-58043D01*
D02*
G37*
G36*
X99964D02*
X99248D01*
X98587Y-58317D01*
X98080Y-58823D01*
X97806Y-59484D01*
Y-60201D01*
X98080Y-60862D01*
X98587Y-61369D01*
X99002Y-61540D01*
Y-62082D01*
X98587Y-62254D01*
X98080Y-62760D01*
X97806Y-63421D01*
Y-64138D01*
X98080Y-64799D01*
X98587Y-65306D01*
X99248Y-65579D01*
X99964D01*
X100626Y-65306D01*
X101132Y-64799D01*
X101406Y-64138D01*
Y-63421D01*
X101132Y-62760D01*
X100626Y-62254D01*
X100211Y-62082D01*
Y-61540D01*
X100626Y-61369D01*
X101132Y-60862D01*
X101406Y-60201D01*
Y-59484D01*
X101132Y-58823D01*
X100626Y-58317D01*
X99964Y-58043D01*
D02*
G37*
G36*
X168862Y-63554D02*
X168146D01*
X167484Y-63828D01*
X166978Y-64335D01*
X166704Y-64996D01*
Y-65712D01*
X166978Y-66374D01*
X167484Y-66880D01*
X168146Y-67154D01*
X168862D01*
X169524Y-66880D01*
X170030Y-66374D01*
X170304Y-65712D01*
Y-64996D01*
X170030Y-64335D01*
X169524Y-63828D01*
X168862Y-63554D01*
D02*
G37*
G36*
X153114D02*
X152398D01*
X151736Y-63828D01*
X151230Y-64335D01*
X150956Y-64996D01*
Y-65712D01*
X151230Y-66374D01*
X151736Y-66880D01*
X152398Y-67154D01*
X153114D01*
X153776Y-66880D01*
X154282Y-66374D01*
X154556Y-65712D01*
Y-64996D01*
X154282Y-64335D01*
X153776Y-63828D01*
X153114Y-63554D01*
D02*
G37*
G36*
X117681D02*
X116965D01*
X116303Y-63828D01*
X115797Y-64335D01*
X115523Y-64996D01*
Y-65712D01*
X115797Y-66374D01*
X116303Y-66880D01*
X116965Y-67154D01*
X117681D01*
X118342Y-66880D01*
X118849Y-66374D01*
X119123Y-65712D01*
Y-64996D01*
X118849Y-64335D01*
X118342Y-63828D01*
X117681Y-63554D01*
D02*
G37*
G36*
X138794Y-66844D02*
X137801D01*
X136883Y-67224D01*
X136181Y-67926D01*
X135801Y-68844D01*
Y-69837D01*
X136181Y-70754D01*
X136883Y-71456D01*
X137801Y-71836D01*
X138794D01*
X139711Y-71456D01*
X140413Y-70754D01*
X140793Y-69837D01*
Y-68844D01*
X140413Y-67926D01*
X139711Y-67224D01*
X138794Y-66844D01*
D02*
G37*
G36*
X246421Y-68279D02*
X245705D01*
X245043Y-68553D01*
X244537Y-69059D01*
X244263Y-69721D01*
Y-70437D01*
X244537Y-71098D01*
X245043Y-71605D01*
X245311Y-71716D01*
X245311Y-72067D01*
X245262Y-72236D01*
X244650Y-72490D01*
X244143Y-72996D01*
X243971Y-73411D01*
X243430D01*
X243258Y-72996D01*
X242752Y-72490D01*
X242337Y-72318D01*
Y-71777D01*
X242752Y-71605D01*
X243258Y-71098D01*
X243532Y-70437D01*
Y-69721D01*
X243258Y-69059D01*
X242752Y-68553D01*
X242090Y-68279D01*
X241374D01*
X240713Y-68553D01*
X240206Y-69059D01*
X239932Y-69721D01*
Y-70437D01*
X240206Y-71098D01*
X240713Y-71605D01*
X241128Y-71777D01*
Y-72318D01*
X240713Y-72490D01*
X240206Y-72996D01*
X239932Y-73658D01*
Y-74374D01*
X240206Y-75035D01*
X240713Y-75542D01*
X241374Y-75816D01*
X242090D01*
X242752Y-75542D01*
X243258Y-75035D01*
X243430Y-74620D01*
X243971D01*
X244143Y-75035D01*
X244650Y-75542D01*
X245311Y-75816D01*
X246027D01*
X246689Y-75542D01*
X247195Y-75035D01*
X247469Y-74374D01*
Y-73658D01*
X247195Y-72996D01*
X246689Y-72490D01*
X246421Y-72379D01*
X246421Y-72027D01*
X246471Y-71858D01*
X247083Y-71605D01*
X247589Y-71098D01*
X247863Y-70437D01*
Y-69721D01*
X247589Y-69059D01*
X247083Y-68553D01*
X246421Y-68279D01*
D02*
G37*
G36*
X157838Y-71428D02*
X157122D01*
X156461Y-71702D01*
X155954Y-72209D01*
X155680Y-72870D01*
Y-73586D01*
X155954Y-74248D01*
X156461Y-74754D01*
X157122Y-75028D01*
X157838D01*
X158500Y-74754D01*
X159006Y-74248D01*
X159280Y-73586D01*
Y-72870D01*
X159006Y-72209D01*
X158500Y-71702D01*
X157838Y-71428D01*
D02*
G37*
G36*
X168862Y-69460D02*
X168146D01*
X167484Y-69734D01*
X166978Y-70240D01*
X166704Y-70902D01*
Y-71618D01*
X166978Y-72280D01*
X167139Y-72441D01*
X166978Y-72602D01*
X166704Y-73264D01*
Y-73980D01*
X166978Y-74642D01*
X167484Y-75148D01*
X168146Y-75422D01*
X168862D01*
X169524Y-75148D01*
X170030Y-74642D01*
X170304Y-73980D01*
Y-73264D01*
X170030Y-72602D01*
X169868Y-72441D01*
X170030Y-72280D01*
X170304Y-71618D01*
Y-70902D01*
X170030Y-70240D01*
X169524Y-69734D01*
X168862Y-69460D01*
D02*
G37*
G36*
X209807Y-70247D02*
X209091D01*
X208429Y-70521D01*
X207923Y-71028D01*
X207649Y-71689D01*
Y-72405D01*
X207923Y-73067D01*
X208084Y-73228D01*
X207923Y-73390D01*
X207649Y-74051D01*
Y-74768D01*
X207923Y-75429D01*
X208429Y-75935D01*
X209091Y-76209D01*
X209807D01*
X210468Y-75935D01*
X210975Y-75429D01*
X211249Y-74768D01*
Y-74051D01*
X210975Y-73390D01*
X210813Y-73228D01*
X210975Y-73067D01*
X211249Y-72405D01*
Y-71689D01*
X210975Y-71028D01*
X210468Y-70521D01*
X209807Y-70247D01*
D02*
G37*
G36*
X110201Y-72610D02*
X109485D01*
X108823Y-72883D01*
X108317Y-73390D01*
X108043Y-74051D01*
Y-74768D01*
X108317Y-75429D01*
X108823Y-75935D01*
X109485Y-76209D01*
X110201D01*
X110862Y-75935D01*
X111369Y-75429D01*
X111643Y-74768D01*
Y-74051D01*
X111369Y-73390D01*
X110862Y-72883D01*
X110201Y-72610D01*
D02*
G37*
G36*
X105870D02*
X105154D01*
X104492Y-72883D01*
X103986Y-73390D01*
X103712Y-74051D01*
Y-74768D01*
X103986Y-75429D01*
X104492Y-75935D01*
X105154Y-76209D01*
X105870D01*
X106531Y-75935D01*
X107038Y-75429D01*
X107312Y-74768D01*
Y-74051D01*
X107038Y-73390D01*
X106531Y-72883D01*
X105870Y-72610D01*
D02*
G37*
G36*
X214531Y-77334D02*
X213815D01*
X213154Y-77608D01*
X212647Y-78114D01*
X212373Y-78776D01*
Y-79492D01*
X212647Y-80154D01*
X213154Y-80660D01*
X213815Y-80934D01*
X214531D01*
X215193Y-80660D01*
X215699Y-80154D01*
X215973Y-79492D01*
Y-78776D01*
X215699Y-78114D01*
X215193Y-77608D01*
X214531Y-77334D01*
D02*
G37*
G36*
X205476Y-77580D02*
X204760D01*
X204099Y-77854D01*
X203592Y-78360D01*
X203318Y-79022D01*
Y-79738D01*
X203592Y-80400D01*
X204099Y-80906D01*
X204760Y-81180D01*
X205476D01*
X206138Y-80906D01*
X206644Y-80400D01*
X206918Y-79738D01*
Y-79022D01*
X206644Y-78360D01*
X206138Y-77854D01*
X205476Y-77580D01*
D02*
G37*
G36*
X168862Y-77728D02*
X168146D01*
X167484Y-78002D01*
X166978Y-78508D01*
X166704Y-79169D01*
Y-79886D01*
X166978Y-80547D01*
X167484Y-81054D01*
X168146Y-81328D01*
X168862D01*
X169524Y-81054D01*
X170030Y-80547D01*
X170304Y-79886D01*
Y-79169D01*
X170030Y-78508D01*
X169524Y-78002D01*
X168862Y-77728D01*
D02*
G37*
G36*
X195299Y-75181D02*
X194465D01*
X193660Y-75397D01*
X192938Y-75814D01*
X192349Y-76403D01*
X191932Y-77125D01*
X191717Y-77930D01*
Y-78763D01*
X191932Y-79568D01*
X192349Y-80290D01*
X192938Y-80879D01*
X193660Y-81296D01*
X194465Y-81512D01*
X195299D01*
X196104Y-81296D01*
X196826Y-80879D01*
X197415Y-80290D01*
X197831Y-79568D01*
X198047Y-78763D01*
Y-77930D01*
X197831Y-77125D01*
X197415Y-76403D01*
X196826Y-75814D01*
X196104Y-75397D01*
X195299Y-75181D01*
D02*
G37*
G36*
X110201Y-78121D02*
X109485D01*
X108823Y-78395D01*
X108317Y-78902D01*
X108043Y-79563D01*
Y-80279D01*
X108317Y-80941D01*
X108823Y-81447D01*
X109485Y-81721D01*
X110201D01*
X110862Y-81447D01*
X111369Y-80941D01*
X111643Y-80279D01*
Y-79563D01*
X111369Y-78902D01*
X110862Y-78395D01*
X110201Y-78121D01*
D02*
G37*
G36*
X105870D02*
X105154D01*
X104492Y-78395D01*
X103986Y-78902D01*
X103712Y-79563D01*
Y-80279D01*
X103986Y-80941D01*
X104492Y-81447D01*
X105154Y-81721D01*
X105870D01*
X106531Y-81447D01*
X107038Y-80941D01*
X107312Y-80279D01*
Y-79563D01*
X107038Y-78902D01*
X106531Y-78395D01*
X105870Y-78121D01*
D02*
G37*
G36*
X198882Y-85995D02*
X198166D01*
X197504Y-86269D01*
X196998Y-86776D01*
X196724Y-87437D01*
Y-88153D01*
X196998Y-88815D01*
X197504Y-89321D01*
X198166Y-89595D01*
X198882D01*
X199543Y-89321D01*
X200050Y-88815D01*
X200324Y-88153D01*
Y-87437D01*
X200050Y-86776D01*
X199543Y-86269D01*
X198882Y-85995D01*
D02*
G37*
G36*
X190122Y-86389D02*
X189406D01*
X188744Y-86663D01*
X188238Y-87169D01*
X187964Y-87831D01*
Y-88547D01*
X188238Y-89209D01*
X188744Y-89715D01*
X189406Y-89989D01*
X190122D01*
X190783Y-89715D01*
X191290Y-89209D01*
X191564Y-88547D01*
Y-87831D01*
X191290Y-87169D01*
X190783Y-86663D01*
X190122Y-86389D01*
D02*
G37*
G36*
X183035Y-92688D02*
X182319D01*
X181658Y-92962D01*
X181151Y-93469D01*
X180877Y-94130D01*
Y-94846D01*
X181151Y-95508D01*
X181177Y-95533D01*
X181264Y-95718D01*
X180757Y-96224D01*
X180483Y-96886D01*
Y-97602D01*
X180757Y-98264D01*
X181264Y-98770D01*
X181925Y-99044D01*
X182641D01*
X183303Y-98770D01*
X183809Y-98264D01*
X184083Y-97602D01*
Y-96886D01*
X183809Y-96224D01*
X183784Y-96199D01*
X183697Y-96014D01*
X184203Y-95508D01*
X184477Y-94846D01*
Y-94130D01*
X184203Y-93469D01*
X183697Y-92962D01*
X183035Y-92688D01*
D02*
G37*
G36*
X197208D02*
X196492D01*
X195831Y-92962D01*
X195324Y-93469D01*
X195050Y-94130D01*
Y-94846D01*
X195324Y-95508D01*
X195831Y-96014D01*
X196041Y-96101D01*
X196120Y-96497D01*
X196093Y-96664D01*
X195838Y-97280D01*
Y-97996D01*
X196112Y-98657D01*
X196618Y-99164D01*
X197280Y-99438D01*
X197996D01*
X198657Y-99164D01*
X199164Y-98657D01*
X199438Y-97996D01*
Y-97280D01*
X199164Y-96618D01*
X198657Y-96112D01*
X198447Y-96025D01*
X198369Y-95629D01*
X198395Y-95462D01*
X198650Y-94846D01*
Y-94130D01*
X198376Y-93469D01*
X197870Y-92962D01*
X197208Y-92688D01*
D02*
G37*
G36*
X181362Y-99381D02*
X180646D01*
X179984Y-99655D01*
X179478Y-100162D01*
X179204Y-100823D01*
Y-101539D01*
X179478Y-102201D01*
X179984Y-102707D01*
X180646Y-102981D01*
X181362D01*
X182024Y-102707D01*
X182530Y-102201D01*
X182804Y-101539D01*
Y-100823D01*
X182530Y-100162D01*
X182024Y-99655D01*
X181362Y-99381D01*
D02*
G37*
G36*
X281854Y-122609D02*
X281138D01*
X280476Y-122883D01*
X279970Y-123390D01*
X279696Y-124051D01*
Y-124767D01*
X279970Y-125429D01*
X280476Y-125935D01*
X281138Y-126209D01*
X281854D01*
X282516Y-125935D01*
X283022Y-125429D01*
X283296Y-124767D01*
Y-124051D01*
X283022Y-123390D01*
X282516Y-122883D01*
X281854Y-122609D01*
D02*
G37*
G36*
X286578Y-123003D02*
X285862D01*
X285201Y-123277D01*
X284695Y-123784D01*
X284420Y-124445D01*
Y-125161D01*
X284695Y-125823D01*
X284918Y-126047D01*
X284711Y-126547D01*
X284288D01*
X283626Y-126821D01*
X283120Y-127327D01*
X282846Y-127988D01*
Y-128705D01*
X283120Y-129366D01*
X283626Y-129872D01*
X284288Y-130147D01*
X285004D01*
X285665Y-129872D01*
X286172Y-129366D01*
X286446Y-128705D01*
Y-127988D01*
X286172Y-127327D01*
X285948Y-127103D01*
X286155Y-126603D01*
X286578D01*
X287240Y-126329D01*
X287746Y-125823D01*
X288020Y-125161D01*
Y-124445D01*
X287746Y-123784D01*
X287240Y-123277D01*
X286578Y-123003D01*
D02*
G37*
G36*
X277008Y-127010D02*
X276292D01*
X275630Y-127284D01*
X275124Y-127791D01*
X274850Y-128452D01*
Y-129168D01*
X275124Y-129830D01*
X275630Y-130336D01*
X276292Y-130610D01*
X277008D01*
X277670Y-130336D01*
X278176Y-129830D01*
X278450Y-129168D01*
Y-128452D01*
X278176Y-127791D01*
X277670Y-127284D01*
X277008Y-127010D01*
D02*
G37*
G36*
X460594Y-85995D02*
X459878D01*
X459217Y-86269D01*
X458710Y-86776D01*
X458436Y-87437D01*
Y-88153D01*
X458710Y-88815D01*
X459217Y-89321D01*
X459878Y-89595D01*
X460594D01*
X461256Y-89321D01*
X461762Y-88815D01*
X462036Y-88153D01*
Y-87437D01*
X461762Y-86776D01*
X461256Y-86269D01*
X460594Y-85995D01*
D02*
G37*
G36*
X455082D02*
X454366D01*
X453705Y-86269D01*
X453198Y-86776D01*
X452924Y-87437D01*
Y-88153D01*
X453198Y-88815D01*
X453705Y-89321D01*
X454366Y-89595D01*
X455082D01*
X455744Y-89321D01*
X456250Y-88815D01*
X456524Y-88153D01*
Y-87437D01*
X456250Y-86776D01*
X455744Y-86269D01*
X455082Y-85995D01*
D02*
G37*
G36*
X455476Y-90720D02*
X454760D01*
X454099Y-90994D01*
X453592Y-91500D01*
X453318Y-92162D01*
Y-92878D01*
X453592Y-93539D01*
X454099Y-94046D01*
X454760Y-94320D01*
X455476D01*
X456138Y-94046D01*
X456644Y-93539D01*
X456918Y-92878D01*
Y-92162D01*
X456644Y-91500D01*
X456138Y-90994D01*
X455476Y-90720D01*
D02*
G37*
G36*
X419256Y-98200D02*
X418540D01*
X417878Y-98474D01*
X417372Y-98980D01*
X417098Y-99642D01*
Y-100358D01*
X417372Y-101020D01*
X417878Y-101526D01*
X418540Y-101800D01*
X419256D01*
X419754Y-101593D01*
X420179Y-101814D01*
X420247Y-101889D01*
Y-102327D01*
X420521Y-102988D01*
X421028Y-103495D01*
X421689Y-103769D01*
X422405D01*
X423067Y-103495D01*
X423573Y-102988D01*
X423847Y-102327D01*
Y-101611D01*
X423573Y-100949D01*
X423067Y-100443D01*
X422405Y-100169D01*
X421689D01*
X421191Y-100375D01*
X420766Y-100155D01*
X420698Y-100079D01*
Y-99642D01*
X420424Y-98980D01*
X419917Y-98474D01*
X419256Y-98200D01*
D02*
G37*
G36*
X445634Y-101743D02*
X444918D01*
X444256Y-102017D01*
X443750Y-102524D01*
X443476Y-103185D01*
Y-103901D01*
X443591Y-104181D01*
X443469Y-104773D01*
X443113Y-105129D01*
X442588Y-105076D01*
X442539Y-105050D01*
X442471Y-104886D01*
X441964Y-104379D01*
X441303Y-104105D01*
X440587D01*
X439925Y-104379D01*
X439419Y-104886D01*
X439145Y-105547D01*
Y-106264D01*
X439419Y-106925D01*
X439925Y-107431D01*
X440587Y-107705D01*
X441303D01*
X441964Y-107431D01*
X442320Y-107076D01*
X442845Y-107128D01*
X442894Y-107155D01*
X442962Y-107319D01*
X443469Y-107825D01*
X444130Y-108099D01*
X444846D01*
X445508Y-107825D01*
X446014Y-107319D01*
X446288Y-106657D01*
Y-105941D01*
X446172Y-105661D01*
X446295Y-105069D01*
X446802Y-104563D01*
X447076Y-103901D01*
Y-103185D01*
X446802Y-102524D01*
X446295Y-102017D01*
X445634Y-101743D01*
D02*
G37*
G36*
X383823D02*
X383106D01*
X382445Y-102017D01*
X381939Y-102524D01*
X381665Y-103185D01*
Y-103901D01*
X381939Y-104563D01*
X382445Y-105069D01*
X383106Y-105343D01*
X383823D01*
X384484Y-105069D01*
X384991Y-104563D01*
X385265Y-103901D01*
Y-103185D01*
X384991Y-102524D01*
X384484Y-102017D01*
X383823Y-101743D01*
D02*
G37*
G36*
X366446Y-83557D02*
X364715D01*
X363005Y-83828D01*
X361358Y-84363D01*
X359816Y-85149D01*
X358415Y-86166D01*
X357190Y-87391D01*
X356173Y-88792D01*
X355387Y-90334D01*
X354852Y-91981D01*
X354581Y-93691D01*
Y-95423D01*
X354852Y-97133D01*
X355387Y-98779D01*
X356173Y-100322D01*
X357190Y-101723D01*
X358415Y-102947D01*
X359816Y-103965D01*
X361358Y-104751D01*
X363005Y-105286D01*
X364715Y-105557D01*
X366446D01*
X368157Y-105286D01*
X369803Y-104751D01*
X371346Y-103965D01*
X372747Y-102947D01*
X373971Y-101723D01*
X374989Y-100322D01*
X375775Y-98779D01*
X376310Y-97133D01*
X376581Y-95423D01*
Y-93691D01*
X376310Y-91981D01*
X375775Y-90334D01*
X374989Y-88792D01*
X373971Y-87391D01*
X372747Y-86166D01*
X371346Y-85149D01*
X369803Y-84363D01*
X368157Y-83828D01*
X366446Y-83557D01*
D02*
G37*
G36*
X391012Y-102710D02*
X390296D01*
X389634Y-102984D01*
X389128Y-103490D01*
X388854Y-104152D01*
Y-104868D01*
X389128Y-105529D01*
X389634Y-106036D01*
X390296Y-106310D01*
X391012D01*
X391673Y-106036D01*
X392180Y-105529D01*
X392454Y-104868D01*
Y-104152D01*
X392180Y-103490D01*
X391673Y-102984D01*
X391012Y-102710D01*
D02*
G37*
G36*
X431854Y-98200D02*
X431138D01*
X430476Y-98474D01*
X429970Y-98980D01*
X429696Y-99642D01*
Y-100358D01*
X429970Y-101020D01*
X430476Y-101526D01*
X431138Y-101800D01*
X431854D01*
X432470Y-101545D01*
X432637Y-101518D01*
X433033Y-101597D01*
X433120Y-101807D01*
X433120Y-101807D01*
X433127Y-101818D01*
X433328Y-102217D01*
X432821Y-102724D01*
X432547Y-103385D01*
Y-104101D01*
X432821Y-104763D01*
X433328Y-105269D01*
X433989Y-105543D01*
X434155D01*
X434420Y-105941D01*
Y-106657D01*
X434694Y-107319D01*
X435201Y-107825D01*
X435862Y-108099D01*
X436579D01*
X437240Y-107825D01*
X437746Y-107319D01*
X438021Y-106657D01*
Y-105941D01*
X437746Y-105280D01*
X437240Y-104773D01*
X436579Y-104499D01*
X436413D01*
X436147Y-104101D01*
Y-103385D01*
X435873Y-102724D01*
X435873Y-102724D01*
X435865Y-102713D01*
X435665Y-102313D01*
X436172Y-101807D01*
X436446Y-101145D01*
Y-100429D01*
X436172Y-99768D01*
X435665Y-99261D01*
X435004Y-98987D01*
X434288D01*
X433672Y-99243D01*
X433504Y-99269D01*
X433109Y-99190D01*
X433022Y-98980D01*
X432516Y-98474D01*
X431854Y-98200D01*
D02*
G37*
G36*
X426342Y-108043D02*
X425626D01*
X424965Y-108317D01*
X424458Y-108823D01*
X424184Y-109485D01*
Y-110201D01*
X424458Y-110862D01*
X424669Y-111073D01*
X424610Y-111368D01*
X424104Y-111874D01*
X423830Y-112536D01*
Y-113252D01*
X423628Y-113554D01*
X423264D01*
X422602Y-113828D01*
X422096Y-114335D01*
X421822Y-114996D01*
Y-115712D01*
X422096Y-116374D01*
X422602Y-116880D01*
X423264Y-117154D01*
X423980D01*
X424642Y-116880D01*
X425148Y-116374D01*
X425422Y-115712D01*
Y-114996D01*
X425624Y-114694D01*
X425988D01*
X426650Y-114420D01*
X427156Y-113913D01*
X427430Y-113252D01*
Y-112536D01*
X427156Y-111874D01*
X426945Y-111663D01*
X427004Y-111369D01*
X427510Y-110862D01*
X427784Y-110201D01*
Y-109485D01*
X427510Y-108823D01*
X427004Y-108317D01*
X426342Y-108043D01*
D02*
G37*
G36*
X416893Y-118968D02*
X416177D01*
X415516Y-119242D01*
X415009Y-119748D01*
X414771Y-120323D01*
D01*
X414735Y-120410D01*
Y-121126D01*
X415009Y-121787D01*
X415516Y-122294D01*
X416177Y-122568D01*
X416893D01*
X417555Y-122294D01*
X418061Y-121787D01*
X418335Y-121126D01*
Y-120410D01*
X418061Y-119748D01*
X417555Y-119242D01*
X416893Y-118968D01*
D02*
G37*
G36*
X408626Y-120247D02*
X407910D01*
X407248Y-120521D01*
X406824Y-120945D01*
D01*
X406742Y-121028D01*
X406468Y-121689D01*
Y-122405D01*
X406742Y-123067D01*
X406903Y-123228D01*
X406742Y-123390D01*
X406468Y-124051D01*
Y-124184D01*
X406335D01*
X405673Y-124458D01*
X405167Y-124965D01*
X404893Y-125626D01*
Y-126342D01*
X405167Y-127004D01*
X405673Y-127510D01*
X406335Y-127784D01*
X407051D01*
X407713Y-127510D01*
X408219Y-127004D01*
X408493Y-126342D01*
Y-126209D01*
X408626D01*
X408912Y-126091D01*
D01*
X409287Y-125935D01*
X409794Y-125429D01*
X410068Y-124767D01*
Y-124051D01*
X409794Y-123390D01*
X409632Y-123228D01*
X409794Y-123067D01*
X410068Y-122405D01*
Y-121689D01*
X409794Y-121028D01*
X409525Y-120759D01*
X409287Y-120521D01*
X408626Y-120247D01*
D02*
G37*
G36*
X401342Y-125302D02*
X400626D01*
X399965Y-125576D01*
X399458Y-126082D01*
X399184Y-126744D01*
Y-126772D01*
Y-127460D01*
X399458Y-128122D01*
X399965Y-128628D01*
X400626Y-128902D01*
X401342D01*
X402004Y-128628D01*
X402510Y-128122D01*
X402784Y-127460D01*
Y-126772D01*
Y-126744D01*
X402510Y-126082D01*
X402004Y-125576D01*
X401342Y-125302D01*
D02*
G37*
G36*
X383441Y-126704D02*
X382724D01*
X382561Y-126772D01*
X382063Y-126978D01*
X381557Y-127484D01*
X381283Y-128146D01*
Y-128862D01*
X381557Y-129524D01*
X382063Y-130030D01*
X382724Y-130304D01*
X383441D01*
X384102Y-130030D01*
X384609Y-129524D01*
X384883Y-128862D01*
Y-128146D01*
X384609Y-127484D01*
X384102Y-126978D01*
X383604Y-126772D01*
X383441Y-126704D01*
D02*
G37*
G36*
X416106Y-127809D02*
X415390D01*
X414728Y-128083D01*
X414222Y-128589D01*
X413948Y-129251D01*
Y-129967D01*
X414222Y-130629D01*
X414728Y-131135D01*
X415390Y-131409D01*
X416106D01*
X416768Y-131135D01*
X416924Y-130979D01*
X417372Y-130773D01*
X417577Y-130979D01*
X417878Y-131279D01*
X418540Y-131553D01*
X419256D01*
X419917Y-131279D01*
X420424Y-130773D01*
X420698Y-130112D01*
Y-129395D01*
X420424Y-128734D01*
X419917Y-128227D01*
X419256Y-127953D01*
X418540D01*
X417878Y-128227D01*
X417722Y-128384D01*
X417274Y-128589D01*
X417068Y-128384D01*
X416768Y-128083D01*
X416106Y-127809D01*
D02*
G37*
G36*
X423193Y-129991D02*
X422477D01*
X421815Y-130265D01*
X421309Y-130772D01*
X421035Y-131433D01*
Y-132149D01*
X421309Y-132811D01*
X421815Y-133317D01*
X422477Y-133591D01*
X423193D01*
X423854Y-133317D01*
X424361Y-132811D01*
X424635Y-132149D01*
Y-131433D01*
X424361Y-130772D01*
X423854Y-130265D01*
X423193Y-129991D01*
D02*
G37*
G36*
Y-142295D02*
X422477D01*
X421815Y-142569D01*
X421309Y-143075D01*
X421035Y-143736D01*
Y-144453D01*
X421309Y-145114D01*
X421815Y-145621D01*
X422477Y-145895D01*
X423193D01*
X423854Y-145621D01*
X424361Y-145114D01*
X424635Y-144453D01*
Y-143736D01*
X424361Y-143075D01*
X423854Y-142569D01*
X423193Y-142295D01*
D02*
G37*
G36*
X418468D02*
X417752D01*
X417091Y-142569D01*
X416584Y-143075D01*
X416310Y-143736D01*
Y-144453D01*
X416584Y-145114D01*
X417091Y-145621D01*
X417752Y-145895D01*
X418468D01*
X419130Y-145621D01*
X419636Y-145114D01*
X419910Y-144453D01*
Y-143736D01*
X419636Y-143075D01*
X419130Y-142569D01*
X418468Y-142295D01*
D02*
G37*
G36*
X427917Y-147019D02*
X427201D01*
X426539Y-147293D01*
X426033Y-147799D01*
X425759Y-148461D01*
Y-149177D01*
X426033Y-149838D01*
X426539Y-150345D01*
X427201Y-150619D01*
X427917D01*
X428579Y-150345D01*
X429085Y-149838D01*
X429359Y-149177D01*
Y-148461D01*
X429085Y-147799D01*
X428579Y-147293D01*
X427917Y-147019D01*
D02*
G37*
G36*
X423193D02*
X422477D01*
X421815Y-147293D01*
X421309Y-147799D01*
X421035Y-148461D01*
Y-149177D01*
X421309Y-149838D01*
X421815Y-150345D01*
X422477Y-150619D01*
X423193D01*
X423854Y-150345D01*
X424361Y-149838D01*
X424635Y-149177D01*
Y-148461D01*
X424361Y-147799D01*
X423854Y-147293D01*
X423193Y-147019D01*
D02*
G37*
G36*
X418468D02*
X417752D01*
X417091Y-147293D01*
X416584Y-147799D01*
X416310Y-148461D01*
Y-149177D01*
X416584Y-149838D01*
X417091Y-150345D01*
X417752Y-150619D01*
X418468D01*
X419130Y-150345D01*
X419636Y-149838D01*
X419910Y-149177D01*
Y-148461D01*
X419636Y-147799D01*
X419130Y-147293D01*
X418468Y-147019D01*
D02*
G37*
G36*
X437169Y-151743D02*
X436453D01*
X435791Y-152017D01*
X435285Y-152524D01*
X435011Y-153185D01*
Y-153901D01*
X435285Y-154563D01*
X435791Y-155069D01*
X436453Y-155343D01*
X437169D01*
X437831Y-155069D01*
X438337Y-154563D01*
X438611Y-153901D01*
Y-153185D01*
X438337Y-152524D01*
X437831Y-152017D01*
X437169Y-151743D01*
D02*
G37*
G36*
X427917D02*
X427201D01*
X426539Y-152017D01*
X426033Y-152524D01*
X425759Y-153185D01*
Y-153901D01*
X426033Y-154563D01*
X426539Y-155069D01*
X427201Y-155343D01*
X427917D01*
X428579Y-155069D01*
X429085Y-154563D01*
X429359Y-153901D01*
Y-153185D01*
X429085Y-152524D01*
X428579Y-152017D01*
X427917Y-151743D01*
D02*
G37*
G36*
X423193D02*
X422477D01*
X421815Y-152017D01*
X421309Y-152524D01*
X421035Y-153185D01*
Y-153901D01*
X421309Y-154563D01*
X421815Y-155069D01*
X422477Y-155343D01*
X423193D01*
X423854Y-155069D01*
X424361Y-154563D01*
X424635Y-153901D01*
Y-153185D01*
X424361Y-152524D01*
X423854Y-152017D01*
X423193Y-151743D01*
D02*
G37*
G36*
X418468D02*
X417752D01*
X417091Y-152017D01*
X416584Y-152524D01*
X416310Y-153185D01*
Y-153901D01*
X416584Y-154563D01*
X417091Y-155069D01*
X417752Y-155343D01*
X418468D01*
X419130Y-155069D01*
X419636Y-154563D01*
X419910Y-153901D01*
Y-153185D01*
X419636Y-152524D01*
X419130Y-152017D01*
X418468Y-151743D01*
D02*
G37*
G36*
X459020Y-163554D02*
X458303D01*
X457642Y-163828D01*
X457413Y-164057D01*
X457087Y-164299D01*
X456760Y-164057D01*
X456531Y-163828D01*
X455870Y-163554D01*
X455154D01*
X454492Y-163828D01*
X454021Y-164299D01*
X453740Y-164318D01*
X453459Y-164299D01*
X452988Y-163828D01*
X452326Y-163554D01*
X451611D01*
X450949Y-163828D01*
X450478Y-164299D01*
X450197Y-164318D01*
X449916Y-164299D01*
X449445Y-163828D01*
X448783Y-163554D01*
X448067D01*
X447406Y-163828D01*
X446899Y-164335D01*
X446625Y-164996D01*
Y-165712D01*
X446899Y-166374D01*
X447406Y-166880D01*
X448067Y-167154D01*
X448783D01*
X449445Y-166880D01*
X449916Y-166409D01*
X450197Y-166390D01*
X450478Y-166409D01*
X450949Y-166880D01*
X451611Y-167154D01*
X452326D01*
X452988Y-166880D01*
X453459Y-166409D01*
X453740Y-166390D01*
X454021Y-166409D01*
X454492Y-166880D01*
X455154Y-167154D01*
X455870D01*
X456531Y-166880D01*
X456760Y-166652D01*
X457087Y-166410D01*
X457413Y-166652D01*
X457642Y-166880D01*
X458303Y-167154D01*
X459020D01*
X459681Y-166880D01*
X460187Y-166374D01*
X460461Y-165712D01*
Y-164996D01*
X460187Y-164335D01*
X459681Y-163828D01*
X459020Y-163554D01*
D02*
G37*
G36*
X443173Y-159947D02*
X442457D01*
X441795Y-160221D01*
X441289Y-160727D01*
X441015Y-161389D01*
Y-162105D01*
X441289Y-162767D01*
X441795Y-163273D01*
X442457Y-163547D01*
Y-164047D01*
X441795Y-164321D01*
X441515Y-164601D01*
X441188Y-164774D01*
X440861Y-164601D01*
X440581Y-164321D01*
X439919Y-164047D01*
X439203D01*
X438542Y-164321D01*
X438035Y-164827D01*
X437761Y-165488D01*
Y-166205D01*
X438035Y-166866D01*
X438542Y-167372D01*
X439203Y-167647D01*
X439919D01*
X440581Y-167372D01*
X440861Y-167092D01*
X441188Y-166919D01*
X441515Y-167092D01*
X441795Y-167372D01*
X442457Y-167647D01*
X443173D01*
X443835Y-167372D01*
X444341Y-166866D01*
X444615Y-166205D01*
Y-165488D01*
X444341Y-164827D01*
X443835Y-164321D01*
X443173Y-164047D01*
Y-163547D01*
X443835Y-163273D01*
X444341Y-162767D01*
X444615Y-162105D01*
Y-161389D01*
X444341Y-160727D01*
X443835Y-160221D01*
X443173Y-159947D01*
D02*
G37*
G36*
X481854Y-195444D02*
X481138D01*
X480476Y-195718D01*
X479970Y-196224D01*
X479696Y-196886D01*
Y-197602D01*
X479970Y-198264D01*
X480476Y-198770D01*
X481138Y-199044D01*
X481854D01*
X482516Y-198770D01*
X483022Y-198264D01*
X483296Y-197602D01*
Y-196886D01*
X483022Y-196224D01*
X482516Y-195718D01*
X481854Y-195444D01*
D02*
G37*
G36*
X522012Y-197019D02*
X521295D01*
X520634Y-197293D01*
X520128Y-197799D01*
X519853Y-198461D01*
Y-199177D01*
X520128Y-199838D01*
X520634Y-200345D01*
X521295Y-200619D01*
X522012D01*
X522673Y-200345D01*
X523179Y-199838D01*
X523454Y-199177D01*
Y-198461D01*
X523179Y-197799D01*
X522673Y-197293D01*
X522012Y-197019D01*
D02*
G37*
G36*
X513744Y-197413D02*
X513028D01*
X512366Y-197687D01*
X511860Y-198193D01*
X511586Y-198855D01*
Y-199571D01*
X511860Y-200232D01*
X512366Y-200739D01*
X513028Y-201013D01*
X513744D01*
X514405Y-200739D01*
X514912Y-200232D01*
X515186Y-199571D01*
Y-198855D01*
X514912Y-198193D01*
X514405Y-197687D01*
X513744Y-197413D01*
D02*
G37*
G36*
X144453Y-78515D02*
X143736D01*
X143075Y-78789D01*
X142569Y-79295D01*
X142295Y-79957D01*
Y-80673D01*
X142569Y-81335D01*
X143075Y-81841D01*
X143736Y-82115D01*
X144453D01*
X145114Y-81841D01*
X145621Y-81335D01*
X145895Y-80673D01*
Y-79957D01*
X145621Y-79295D01*
X145114Y-78789D01*
X144453Y-78515D01*
D02*
G37*
G36*
X133457Y-118184D02*
X132741D01*
X132079Y-118458D01*
X131573Y-118964D01*
X131299Y-119626D01*
Y-120342D01*
X131573Y-121003D01*
X132079Y-121510D01*
X132741Y-121784D01*
X133457D01*
X134118Y-121510D01*
X134625Y-121003D01*
X134899Y-120342D01*
Y-119626D01*
X134625Y-118964D01*
X134118Y-118458D01*
X133457Y-118184D01*
D02*
G37*
G36*
X448987Y-213889D02*
X448158D01*
X447393Y-214206D01*
X446807Y-214792D01*
X446490Y-215558D01*
Y-216387D01*
X446807Y-217152D01*
X447393Y-217738D01*
X448158Y-218055D01*
X448987D01*
X449753Y-217738D01*
X450339Y-217152D01*
X450656Y-216387D01*
Y-215558D01*
X450339Y-214792D01*
X449753Y-214206D01*
X448987Y-213889D01*
D02*
G37*
G36*
X452032Y-223084D02*
X451315D01*
X450654Y-223359D01*
X450148Y-223865D01*
X449873Y-224527D01*
Y-225243D01*
X450148Y-225904D01*
X450654Y-226411D01*
X451315Y-226684D01*
X452032D01*
X452693Y-226411D01*
X453199Y-225904D01*
X453474Y-225243D01*
Y-224527D01*
X453199Y-223865D01*
X452693Y-223359D01*
X452032Y-223084D01*
D02*
G37*
%LPD*%
D11*
X408760Y-238189D02*
X410630Y-236319D01*
Y-219291D01*
X407874Y-216535D02*
X410630Y-219291D01*
X398191Y-215982D02*
X407320D01*
X407874Y-216535D01*
X396457Y-217717D02*
X398191Y-215982D01*
X390158Y-217717D02*
X396457D01*
X382629Y-194440D02*
X390158Y-201969D01*
Y-217717D02*
Y-201969D01*
X375066Y-194440D02*
X382629D01*
X373238Y-196268D02*
X375066Y-194440D01*
X373238Y-198809D02*
Y-196268D01*
X368232Y-203816D02*
X373238Y-198809D01*
X368232Y-217717D02*
Y-203816D01*
X235039Y-125984D02*
X240178D01*
X245325Y-120837D01*
X223209Y-137815D02*
X235039Y-125984D01*
D16*
X261970Y-383762D02*
G03*
X261221Y-384512I0J-750D01*
G01*
X263119Y-380762D02*
G03*
X263119Y-379262I0J750D01*
G01*
X261789Y-380762D02*
G03*
X261789Y-382262I0J-750D01*
G01*
X263029Y-383762D02*
G03*
X263029Y-382262I0J750D01*
G01*
X262369Y-378512D02*
G03*
X263119Y-379262I750J0D01*
G01*
X385646Y-349727D02*
G03*
X385568Y-349885I403J-296D01*
G01*
X385646Y-344575D02*
G03*
X385746Y-342798I-15740J1777D01*
G01*
X385366Y-350374D02*
G03*
X385309Y-350541I437J-243D01*
G01*
X385013Y-350837D02*
G03*
X385019Y-350831I-1518J1524D01*
G01*
X385366Y-350374D02*
G03*
X385568Y-349885I-1871J1061D01*
G01*
X379311Y-356609D02*
G03*
X379361Y-356489I-121J120D01*
G01*
X369255Y-336438D02*
G03*
X369311Y-336473I5525J8940D01*
G01*
X369315Y-336475D02*
G03*
X369341Y-336489I251J432D01*
G01*
X368675Y-336053D02*
G03*
X369255Y-336438I6105J8555D01*
G01*
X368110Y-330330D02*
G03*
X367282Y-332329I1999J-1999D01*
G01*
Y-333858D02*
G03*
X367849Y-335227I1936J0D01*
G01*
X376563Y-359286D02*
G03*
X377175Y-358745I-4101J5254D01*
G01*
X372220Y-360598D02*
G03*
X372462Y-360698I241J241D01*
G01*
D02*
G03*
X373612Y-360598I0J6665D01*
G01*
X323071Y-355472D02*
G03*
X318698Y-353661I-4373J-4373D01*
G01*
X278959D02*
G03*
X278363Y-353684I0J-7664D01*
G01*
X327706Y-359773D02*
G03*
X330078Y-360598I2572J3573D01*
G01*
X326287Y-358687D02*
G03*
X327706Y-359773I4783J4783D01*
G01*
X268486Y-360960D02*
G03*
X265557Y-368031I7071J-7071D01*
G01*
X265092Y-374161D02*
G03*
X265557Y-373033I-1135J1128D01*
G01*
X262515Y-376738D02*
G03*
X262369Y-377091I354J-353D01*
G01*
X261221Y-386262D02*
G03*
X261367Y-386616I500J0D01*
G01*
X378726Y-336958D02*
G03*
X378605Y-337008I0J-171D01*
G01*
X380755D02*
G03*
X380155Y-336958I-600J-3571D01*
G01*
X382716Y-338018D02*
G03*
X380755Y-337008I-2561J-2561D01*
G01*
X385746Y-342341D02*
G03*
X384832Y-340135I-3119J0D01*
G01*
X366182Y-333858D02*
G03*
X367072Y-336005I3036J0D01*
G01*
X366182Y-332329D02*
G03*
X365354Y-330330I-2827J0D01*
G01*
X378976Y-355459D02*
G03*
X378855Y-355509I0J-171D01*
G01*
X372220Y-359598D02*
G03*
X376568Y-357797I0J6148D01*
G01*
X323524Y-354370D02*
G03*
X319154Y-352561I-4371J-4376D01*
G01*
X279927D02*
G03*
X272078Y-355812I0J-11100D01*
G01*
X267708Y-360182D02*
G03*
X264457Y-368031I7849J-7849D01*
G01*
X264312Y-373385D02*
G03*
X264457Y-373033I-355J352D01*
G01*
X264306Y-387253D02*
G03*
X263814Y-387648I-3J-500D01*
G01*
X260039Y-387593D02*
G03*
X260055Y-387716I500J0D01*
G01*
X378149Y-338008D02*
G03*
X378270Y-338058I121J121D01*
G01*
X382260Y-339119D02*
G03*
X379699Y-338058I-2561J-2561D01*
G01*
X384646Y-342341D02*
G03*
X384054Y-340913I-2019J0D01*
G01*
X384310Y-350125D02*
G03*
X384646Y-349313I-815J812D01*
G01*
X384309Y-350127D02*
G03*
X384310Y-350125I-814J814D01*
G01*
X369341Y-336489D02*
G03*
X371546Y-337008I2216J4475D01*
G01*
X373612Y-360598D02*
G03*
X376563Y-359286I-1150J6565D01*
G01*
X278363Y-353684D02*
G03*
X278329Y-353688I41J-498D01*
G01*
Y-353688D02*
G03*
X274006Y-355479I1598J-9973D01*
G01*
D02*
G03*
X273979Y-355500I296J-403D01*
G01*
D02*
G03*
X273540Y-355906I4980J-5825D01*
G01*
X367319Y-336252D02*
G03*
X371557Y-338008I4238J4238D01*
G01*
X323527Y-354372D02*
G03*
X323524Y-354370I-4373J-4373D01*
G01*
X327064Y-357910D02*
G03*
X331139Y-359598I4075J4075D01*
G01*
X262268Y-375487D02*
G03*
X262388Y-375355I-303J397D01*
G01*
X262268Y-375487D02*
G03*
X262139Y-375587I3362J-4466D01*
G01*
X260055Y-387716D02*
G03*
X263814Y-387648I1871J478D01*
G01*
X365002Y-355169D02*
G03*
X366465Y-354801I-195J3876D01*
G01*
X365392Y-356169D02*
G03*
X366568Y-355853I-802J5343D01*
G01*
X336023Y-355224D02*
G03*
X338305Y-356169I2840J3630D01*
G01*
X367946Y-355057D02*
G03*
X368200Y-354895I-2508J4240D01*
G01*
X367015Y-355639D02*
G03*
X367797Y-355130I-4448J7694D01*
G01*
X367946Y-355057D02*
G03*
X367797Y-355130I143J-479D01*
G01*
X336023Y-355224D02*
G03*
X335912Y-355158I-306J-396D01*
G01*
X368200Y-354895D02*
G03*
X368921Y-354300I-2763J4079D01*
G01*
X333266Y-352654D02*
G03*
X334244Y-353490I5793J5782D01*
G01*
X373700Y-346573D02*
G03*
X373287Y-347573I999J-999D01*
G01*
X372865Y-350356D02*
G03*
X373287Y-349339I-1017J1017D01*
G01*
X331867Y-351255D02*
G03*
X327882Y-349606I-3981J-3981D01*
G01*
X263943D02*
G03*
X262992Y-350000I822J-3329D01*
G01*
X256235Y-356757D02*
G03*
X253306Y-363828I7071J-7071D01*
G01*
X250978Y-372280D02*
G03*
X253306Y-366660I-5620J5620D01*
G01*
X246260Y-386706D02*
G03*
X246339Y-386975I500J-0D01*
G01*
X372186Y-347573D02*
G03*
X371773Y-346573I-1413J0D01*
G01*
X371305Y-350360D02*
G03*
X372186Y-348233I-2127J2127D01*
G01*
X264765Y-348506D02*
G03*
X261633Y-349803I0J-4429D01*
G01*
X252235Y-363028D02*
G03*
X252206Y-363828I11071J-800D01*
G01*
X248559Y-387253D02*
G03*
X248067Y-387647I-3J-500D01*
G01*
X242760Y-382451D02*
G03*
X245198Y-388465I8651J6D01*
G01*
X245201Y-388468D02*
G03*
X248067Y-387647I1213J1180D01*
G01*
X332643Y-350476D02*
G03*
X327890Y-348506I-4753J-4751D01*
G01*
X336326Y-354158D02*
G03*
X338765Y-355169I2439J2439D01*
G01*
X246410Y-376848D02*
G03*
X246324Y-376964I353J-353D01*
G01*
X247024Y-383395D02*
G03*
X247024Y-381894I0J750D01*
G01*
X246324Y-376964D02*
G03*
X246264Y-377201I440J-237D01*
G01*
X245513Y-380395D02*
G03*
X246263Y-379645I0J750D01*
G01*
X245513Y-380395D02*
G03*
X245513Y-381894I0J-750D01*
G01*
X244921Y-383395D02*
G03*
X244921Y-384894I0J-750D01*
G01*
X246260Y-385645D02*
G03*
X245511Y-384894I-750J0D01*
G01*
X366465Y-354801D02*
G03*
X368144Y-353522I-3899J6857D01*
G01*
X245247Y-376455D02*
G03*
X242760Y-382451I5995J-6000D01*
G01*
X250197Y-371505D02*
G03*
X252206Y-366655I-4850J4850D01*
G01*
X255457Y-355979D02*
G03*
X252235Y-363028I7849J-7849D01*
G01*
X359439Y-349990D02*
G03*
X359901Y-348876I-1114J1114D01*
G01*
X236673Y-366113D02*
G03*
X239920Y-358273I-7840J7840D01*
G01*
X360315Y-346573D02*
G03*
X359901Y-347573I999J-999D01*
G01*
X355390Y-352362D02*
G03*
X358253Y-351176I0J4049D01*
G01*
X234833Y-367953D02*
G03*
X232208Y-372251I7581J-7581D01*
G01*
X229331Y-387253D02*
G03*
X230556Y-385679I-5703J5703D01*
G01*
X257453Y-344882D02*
G03*
X250382Y-347811I0J-10000D01*
G01*
X353244Y-352362D02*
G03*
X353258Y-352362I14J9765D01*
G01*
X346352Y-349502D02*
G03*
X353244Y-352362I6905J6905D01*
G01*
X342520Y-345669D02*
G03*
X340619Y-344882I-1901J-1901D01*
G01*
X229180Y-385410D02*
G03*
X231129Y-387687I151J-1844D01*
G01*
X239132Y-357505D02*
G03*
X238820Y-358259I754J-754D01*
G01*
X230464Y-374724D02*
G03*
X230463Y-374763I499J-39D01*
G01*
X234046Y-367184D02*
G03*
X232307Y-369489I7360J-7360D01*
G01*
X355163Y-351262D02*
G03*
X357635Y-350239I0J3499D01*
G01*
X231921Y-387253D02*
G03*
X231463Y-387326I0J-1480D01*
G01*
X232307Y-369489D02*
G03*
X230464Y-374724I8931J-6086D01*
G01*
X257453Y-343782D02*
G03*
X249605Y-347033I0J-11100D01*
G01*
X235891Y-365339D02*
G03*
X238820Y-358268I-7071J7071D01*
G01*
X231463Y-387326D02*
G03*
X231131Y-387679I153J-476D01*
G01*
X358801Y-347573D02*
G03*
X358387Y-346573I-1413J0D01*
G01*
X358661Y-349213D02*
G03*
X358662Y-349212I-336J336D01*
G01*
D02*
G03*
X358801Y-348876I-337J335D01*
G01*
X229180Y-385410D02*
G03*
X229573Y-385160I-41J498D01*
G01*
X353699Y-351262D02*
G03*
X353713Y-351262I14J9765D01*
G01*
X346808Y-348402D02*
G03*
X353699Y-351262I6905J6905D01*
G01*
X343298Y-344892D02*
G03*
X340619Y-343782I-2679J-2679D01*
G01*
X232208Y-372251D02*
G03*
X232131Y-372501I10206J-3282D01*
G01*
X231849Y-374446D02*
G03*
X232591Y-375304I742J-108D01*
G01*
X233291Y-376804D02*
G03*
X233291Y-375304I0J750D01*
G01*
X232213Y-376804D02*
G03*
X232213Y-378304I0J-750D01*
G01*
X233739Y-379804D02*
G03*
X233739Y-378304I0J750D01*
G01*
X232443Y-379804D02*
G03*
X231693Y-380554I0J-750D01*
G01*
X230556Y-385679D02*
G03*
X230699Y-385429I-6928J4128D01*
G01*
X357635Y-350239D02*
G03*
X357637Y-350237I-2472J2476D01*
G01*
X229789Y-384818D02*
G03*
X229864Y-384653I-410J286D01*
G01*
X229789Y-384818D02*
G03*
X229573Y-385160I3743J-2610D01*
G01*
X230463Y-382229D02*
G03*
X230463Y-382226I-500J3D01*
G01*
X230448Y-382347D02*
G03*
X230463Y-382229I-485J121D01*
G01*
X351770Y-338317D02*
G03*
X351801Y-338301I-2164J4169D01*
G01*
X351833Y-338286D02*
G03*
X353576Y-337105I-2227J5164D01*
G01*
D02*
G03*
X355269Y-333497I-4120J4133D01*
G01*
X355292Y-333386D02*
G03*
X355269Y-333497I474J-159D01*
G01*
X356090Y-330822D02*
G03*
X356299Y-330315I-509J507D01*
G01*
X349606Y-338846D02*
G03*
X351770Y-338317I-0J4697D01*
G01*
X351833Y-338286D02*
G03*
X351801Y-338301I200J-458D01*
G01*
X355292Y-332813D02*
G03*
X355392Y-331520I-8315J1293D01*
G01*
X217253Y-388562D02*
G03*
X217903Y-386760I-1592J1592D01*
G01*
X214137Y-387647D02*
G03*
X213646Y-387253I-489J-106D01*
G01*
X214137Y-387647D02*
G03*
X217253Y-388562I1808J394D01*
G01*
X310269Y-337764D02*
G03*
X312881Y-338846I2612J2612D01*
G01*
X300631Y-328126D02*
G03*
X293560Y-325197I-7071J-7071D01*
G01*
X248353D02*
G03*
X246482Y-325972I1014J-5094D01*
G01*
X229620Y-342834D02*
G03*
X226691Y-349905I7071J-7071D01*
G01*
X226128Y-378535D02*
G03*
X226691Y-376680I-2778J1855D01*
G01*
X225712Y-379042D02*
G03*
X226128Y-378535I-2362J2362D01*
G01*
X225557Y-379106D02*
G03*
X225712Y-379042I0J220D01*
G01*
X223000Y-379138D02*
G03*
X221939Y-379138I-530J-530D01*
G01*
X224060Y-379138D02*
X224061Y-379138D01*
X223000D02*
G03*
X224060Y-379138I530J530D01*
G01*
X221939Y-379138D02*
G03*
X221939Y-380199I530J-530D01*
G01*
X221939Y-381259D02*
G03*
X221939Y-380199I-530J530D01*
G01*
X220879Y-381259D02*
G03*
X221939Y-381259I530J530D01*
G01*
X220632Y-381013D02*
X220631Y-381012D01*
X219818Y-383381D02*
G03*
X219818Y-382320I-530J530D01*
G01*
X220631Y-381012D02*
G03*
X219571Y-381013I-530J-531D01*
G01*
D02*
G03*
X219571Y-382073I530J-530D01*
G01*
X218757Y-383381D02*
G03*
X219818Y-383381I530J530D01*
G01*
X218428Y-383051D02*
X218427Y-383051D01*
D02*
G03*
X217367Y-383051I-530J-531D01*
G01*
D02*
G03*
X217367Y-384112I530J-530D01*
G01*
X217697Y-385502D02*
G03*
X217697Y-384442I-531J530D01*
G01*
X217696Y-384441D01*
Y-385502D02*
X217697Y-385502D01*
X353543Y-330315D02*
G03*
X353754Y-330823I719J0D01*
G01*
X354143Y-331212D02*
G03*
X354142Y-331211I-363J-362D01*
G01*
X354292Y-331574D02*
G03*
X354143Y-331212I-512J0D01*
G01*
X349606Y-337746D02*
G03*
X352876Y-336391I0J4624D01*
G01*
X308878Y-334817D02*
G03*
X315949Y-337746I7071J7071D01*
G01*
X301409Y-327348D02*
G03*
X293560Y-324097I-7849J-7849D01*
G01*
X249367D02*
G03*
X244987Y-325911I0J-6194D01*
G01*
X228842Y-342056D02*
G03*
X225590Y-349905I7849J-7849D01*
G01*
X352876Y-336391D02*
G03*
X354292Y-332972I-3419J3419D01*
G01*
X224824Y-378374D02*
G03*
X225590Y-376524I-1850J1850D01*
G01*
X263647Y-375606D02*
X265092Y-374161D01*
X377175Y-358745D02*
X379311Y-356609D01*
X385646Y-349727D02*
Y-344575D01*
X385646Y-349727D02*
X385646Y-349727D01*
X260039Y-377638D02*
X261677Y-376000D01*
X260039Y-379953D02*
Y-377638D01*
Y-387593D02*
Y-379953D01*
X385019Y-350831D02*
X385309Y-350541D01*
X263596Y-375657D02*
X263647Y-375606D01*
X261789Y-380762D02*
X263119D01*
X261221Y-386013D02*
Y-384512D01*
X261789Y-382262D02*
X263029D01*
X261221Y-386013D02*
X261221Y-386262D01*
X261970Y-383762D02*
X263029D01*
X263119Y-379262D02*
X263119D01*
X379361Y-356489D02*
X385013Y-350837D01*
X262515Y-376738D02*
X263596Y-375657D01*
X385746Y-342798D02*
Y-342341D01*
X385309Y-350541D02*
Y-350541D01*
X367849Y-335227D02*
X368675Y-336053D01*
X369311Y-336473D02*
X369315Y-336475D01*
X368110Y-330330D02*
Y-330315D01*
X368675Y-336053D02*
X368675Y-336053D01*
X262369Y-378512D02*
Y-377091D01*
X263596Y-375657D02*
X263596D01*
X263596D01*
X367282Y-333858D02*
Y-332329D01*
X278959Y-353661D02*
X318698D01*
X330078Y-360598D02*
X372220D01*
X323071Y-355472D02*
X326287Y-358687D01*
X268486Y-360960D02*
X273540Y-355906D01*
X265557Y-373033D02*
Y-368031D01*
X368675Y-336053D02*
Y-336053D01*
X371546Y-337008D02*
X378605D01*
X263647Y-375606D02*
X263647D01*
X378726Y-336958D02*
X380155D01*
X382716Y-338018D02*
X384832Y-340135D01*
X366182Y-333858D02*
Y-332329D01*
X371557Y-338008D02*
X378149D01*
X365354Y-330330D02*
Y-330315D01*
X378976Y-355459D02*
X384309Y-350127D01*
X261677Y-376000D02*
X262090Y-375587D01*
X376568Y-357797D02*
X378855Y-355509D01*
X279927Y-352561D02*
X319154D01*
X331139Y-359598D02*
X372220D01*
X264457Y-373033D02*
Y-368031D01*
X262468Y-375229D02*
X264312Y-373385D01*
X264306Y-387253D02*
X265158D01*
X262090Y-375587D02*
X262139D01*
X378270Y-338058D02*
X379699D01*
X382260Y-339119D02*
X384054Y-340913D01*
X384646Y-349313D02*
Y-342341D01*
X378605Y-337008D02*
X378605Y-337008D01*
X261367Y-386616D02*
X262006Y-387255D01*
X367072Y-336005D02*
X367319Y-336252D01*
X323527Y-354372D02*
X327064Y-357910D01*
X267708Y-360182D02*
X272078Y-355812D01*
X262388Y-375355D02*
X262468Y-375229D01*
X338765Y-355169D02*
X365002D01*
X338305Y-356169D02*
X365392D01*
X366800Y-355853D02*
X367015Y-355639D01*
X366568Y-355853D02*
X366800D01*
X334244Y-353490D02*
X335912Y-355158D01*
X331867Y-351255D02*
X333266Y-352654D01*
X373700Y-346573D02*
X374114Y-346159D01*
X373287Y-349339D02*
Y-347573D01*
X331867Y-351255D02*
Y-351255D01*
X368921Y-354300D02*
X372865Y-350356D01*
X263943Y-349606D02*
X327882D01*
X256235Y-356757D02*
X262992Y-350000D01*
X253306Y-366660D02*
Y-363828D01*
X246410Y-376848D02*
X250978Y-372280D01*
X246339Y-386975D02*
X246339Y-386975D01*
X246260Y-386706D02*
X246260D01*
X372186Y-348233D02*
Y-347573D01*
X368144Y-353522D02*
X371305Y-350360D01*
X327890Y-348506D02*
X327890D01*
X264765D02*
X327890D01*
X252206Y-366655D02*
Y-363828D01*
X248559Y-387253D02*
X249410D01*
X245198Y-388465D02*
X245201Y-388468D01*
X332643Y-350476D02*
Y-350476D01*
X332967Y-350799D02*
X336326Y-354158D01*
X374114Y-346159D02*
Y-346144D01*
X245513Y-381894D02*
X247024D01*
X244921Y-383395D02*
X247024D01*
X246264Y-377201D02*
X246264Y-377201D01*
X246264Y-377214D02*
X246264Y-377201D01*
X246263Y-379645D02*
X246264Y-377214D01*
X245513Y-380395D02*
X245513D01*
X244921Y-384894D02*
X245511D01*
X246260Y-386020D02*
X246260Y-385645D01*
X246260Y-386270D02*
X246260Y-386020D01*
X246260Y-386706D02*
X246260Y-386270D01*
X245247Y-376455D02*
X250197Y-371505D01*
X255457Y-355979D02*
X261633Y-349803D01*
X371359Y-346159D02*
Y-346144D01*
Y-346159D02*
X371773Y-346573D01*
X332643Y-350476D02*
X332967Y-350799D01*
Y-350799D02*
Y-350799D01*
X234833Y-367953D02*
X234833Y-367953D01*
X353258Y-352362D02*
X355390D01*
X257453Y-344882D02*
X340619D01*
X360315Y-346573D02*
X360729Y-346159D01*
X234833Y-367953D02*
X236673Y-366113D01*
X359901Y-348876D02*
Y-347573D01*
X358253Y-351176D02*
X359439Y-349990D01*
X239920Y-358273D02*
X250382Y-347811D01*
X342520Y-345669D02*
X346352Y-349502D01*
X358661Y-349213D02*
X358662Y-349212D01*
X357637Y-350237D02*
X358661Y-349213D01*
X234046Y-367184D02*
X235891Y-365339D01*
X232307Y-369489D02*
Y-369489D01*
X229180Y-385410D02*
X229180Y-385410D01*
X353713Y-351262D02*
X355163D01*
X239132Y-357505D02*
X249605Y-347033D01*
X231129Y-387687D02*
X231131Y-387679D01*
X238820Y-358268D02*
Y-358259D01*
X231921Y-387253D02*
X232480D01*
X358801Y-348876D02*
Y-347573D01*
X230463Y-381349D02*
X230463Y-374763D01*
X358661Y-349213D02*
X358662Y-349212D01*
X358661Y-349213D02*
X358661Y-349213D01*
X231463Y-387326D02*
Y-387326D01*
X230464Y-374724D02*
X230464D01*
X257453Y-343782D02*
X340619D01*
X360729Y-346159D02*
Y-346144D01*
X231849Y-374446D02*
X232131Y-372501D01*
X232591Y-375304D02*
X233291D01*
X232213Y-376804D02*
X233291D01*
X232213Y-378304D02*
X233739D01*
X232443Y-379804D02*
X233739D01*
X231693Y-381505D02*
X231693Y-380554D01*
X231693Y-381505D02*
Y-381505D01*
X230699Y-385429D02*
X231693Y-381505D01*
X230556Y-385679D02*
X230556Y-385679D01*
X230463Y-382226D02*
Y-381349D01*
X229864Y-384653D02*
X230249Y-383132D01*
X230253Y-383117D02*
X230448Y-382347D01*
X357973Y-346159D02*
X358387Y-346573D01*
X230250Y-383131D02*
X230253Y-383117D01*
X230249Y-383132D02*
X230250Y-383131D01*
X357973Y-346159D02*
Y-346144D01*
X343298Y-344892D02*
X346808Y-348402D01*
X355292Y-333386D02*
X355292Y-332813D01*
X355392Y-331520D02*
X356090Y-330822D01*
X217903Y-386760D02*
X225557Y-379106D01*
X213646Y-387253D02*
X213646D01*
X212795D02*
X213646D01*
X312881Y-338846D02*
X349606D01*
X300631Y-328126D02*
X310269Y-337764D01*
X248353Y-325197D02*
X248353Y-325197D01*
X293560D01*
X248353D02*
X248353D01*
X229620Y-342834D02*
X246482Y-325972D01*
X226691Y-376680D02*
Y-349905D01*
X224061Y-379138D02*
X224824Y-378374D01*
X223000Y-379138D02*
X223000Y-379138D01*
X224060Y-379138D02*
X224061Y-379138D01*
X223000Y-379138D02*
X223000Y-379138D01*
X221939Y-380199D02*
X221939Y-380199D01*
X220632Y-381013D02*
X220879Y-381259D01*
X220631Y-381012D02*
X220632Y-381013D01*
X219818Y-382320D02*
X219818Y-382320D01*
X219571Y-382073D02*
X219818Y-382320D01*
X218428Y-383051D02*
X218757Y-383381D01*
X218427Y-383051D02*
X218428Y-383051D01*
X217367Y-384112D02*
X217696Y-384441D01*
X217697Y-384442D01*
X217696Y-385502D02*
X217697Y-385502D01*
X215945Y-387253D02*
X217696Y-385502D01*
X354142Y-331211D02*
X354143Y-331212D01*
X353754Y-330823D02*
X354142Y-331211D01*
X354292Y-332972D02*
Y-331574D01*
X315949Y-337746D02*
X349606D01*
X249367Y-324097D02*
X293560D01*
X225590Y-376524D02*
Y-349905D01*
X301409Y-327348D02*
X308878Y-334817D01*
X228842Y-342056D02*
X244987Y-325911D01*
D17*
X317860Y-293701D02*
X320875D01*
X336364Y-292913D02*
X345161D01*
X324213Y-290364D02*
X333814D01*
X336364Y-292913D01*
X320875Y-293701D02*
X324213Y-290364D01*
X281890Y-276772D02*
X291732D01*
X298819Y-269685D01*
X278141Y-280520D02*
X281890Y-276772D01*
X278141Y-290066D02*
Y-280520D01*
X279020Y-290945D02*
X281496D01*
X278141Y-290066D02*
X279020Y-290945D01*
X281496D02*
X282759Y-289682D01*
X291598D01*
X291907Y-289991D02*
X299709D01*
X291598Y-289682D02*
X291907Y-289991D01*
X299709D02*
X299875Y-290158D01*
X314316D01*
X317860Y-293701D01*
X52805Y-50787D02*
X66102Y-64085D01*
X35433Y-50787D02*
X52805D01*
D18*
X61417Y-140100D02*
Y-127117D01*
X65175Y-143857D02*
X138033D01*
X61417Y-140100D02*
X65175Y-143857D01*
X58710Y-124409D02*
X61417Y-127117D01*
X138033Y-143857D02*
X148205Y-133685D01*
X46850Y-124409D02*
X58710D01*
X173622Y-121653D02*
X213386D01*
X222351Y-101969D02*
Y-98694D01*
X220079Y-104241D02*
X222351Y-101969D01*
X213386Y-121653D02*
X220079Y-114961D01*
Y-104241D01*
X161591Y-133685D02*
X173622Y-121653D01*
X148205Y-133685D02*
X161591D01*
X44001Y-137747D02*
Y-127259D01*
X46850Y-124409D01*
X161994Y-105512D02*
X164843Y-108360D01*
Y-114040D02*
Y-108360D01*
X158971Y-105512D02*
X161994D01*
X153150Y-99691D02*
X158971Y-105512D01*
X164681Y-114040D02*
X164843D01*
X164518Y-114202D02*
X164681Y-114040D01*
X157474Y-114202D02*
X164518D01*
X156687Y-113414D02*
X157474Y-114202D01*
X153178Y-113414D02*
X156687D01*
X153150Y-113386D02*
X153178Y-113414D01*
X252614Y-291480D02*
Y-277518D01*
X247537Y-272441D02*
X252614Y-277518D01*
X231496Y-272441D02*
X247537D01*
X226378Y-267323D02*
X231496Y-272441D01*
X226378Y-267323D02*
Y-252756D01*
X236673Y-242460D01*
X264450D01*
X268718Y-246728D01*
X275464D02*
X275538Y-246654D01*
X268718Y-246728D02*
X275464D01*
X276640Y-246654D02*
X276755Y-246539D01*
X275538Y-246654D02*
X276640D01*
X153937Y-298819D02*
X245276D01*
X252614Y-291480D01*
X103937Y-348819D02*
X153937Y-298819D01*
X26772Y-348819D02*
X103937D01*
D25*
X495596Y-307087D02*
X498705Y-303978D01*
X496620Y-310492D02*
X499350D01*
X501695Y-308148D02*
Y-305284D01*
X499350Y-310492D02*
X501695Y-308148D01*
X498705Y-303978D02*
X500388D01*
X501695Y-305284D01*
X487222Y-302970D02*
X491339Y-307087D01*
X495596D01*
X460778Y-299771D02*
X463977Y-302970D01*
X487222D01*
X413348Y-299771D02*
X460778D01*
X410821Y-297244D02*
X413348Y-299771D01*
X415968Y-293527D02*
X420184Y-297743D01*
X461129D02*
X464373Y-300987D01*
X420184Y-297743D02*
X461129D01*
X359766Y-297244D02*
X410821D01*
X356223Y-293701D02*
X359766Y-297244D01*
X330709Y-294882D02*
X351575D01*
X352756Y-293701D01*
X356223D01*
X325776D02*
X329528D01*
X330709Y-294882D01*
X355748Y-290788D02*
X358487Y-293527D01*
X415968D01*
X548674Y-328925D02*
X559801D01*
X585132Y-219198D02*
Y-196757D01*
X551575Y-252756D02*
X585132Y-219198D01*
X561536Y-306180D02*
X562992Y-304724D01*
X561536Y-327190D02*
Y-306180D01*
X559801Y-328925D02*
X561536Y-327190D01*
X562992Y-304724D02*
Y-300928D01*
X551119Y-289054D02*
X562992Y-300928D01*
X551119Y-283527D02*
X551700Y-282946D01*
X551119Y-289054D02*
Y-283527D01*
X551575Y-254473D02*
Y-252756D01*
Y-254473D02*
X551700Y-254598D01*
Y-282946D02*
Y-254598D01*
X548814Y-326946D02*
X556407D01*
X560236Y-323116D01*
X554993Y-295938D02*
X560236Y-301181D01*
Y-323116D02*
Y-301181D01*
X551108Y-295938D02*
X554993D01*
X546457Y-291286D02*
Y-254724D01*
Y-291286D02*
X551108Y-295938D01*
X568504Y-232677D02*
Y-231102D01*
X546457Y-254724D02*
X568504Y-232677D01*
X576632Y-222974D02*
Y-182522D01*
X568504Y-231102D02*
X576632Y-222974D01*
X568957Y-222382D02*
X574803Y-216535D01*
X559842Y-237402D02*
X568957Y-228288D01*
X555512Y-301575D02*
X557087Y-303150D01*
Y-315245D02*
Y-303150D01*
X553937Y-301575D02*
X555512D01*
X551968Y-303543D02*
X553937Y-301575D01*
X547638Y-303543D02*
X551968D01*
X544291Y-300197D02*
X547638Y-303543D01*
X544291Y-300197D02*
Y-253896D01*
X559842Y-238345D02*
Y-237402D01*
X544291Y-253896D02*
X559842Y-238345D01*
X568957Y-228288D02*
Y-222382D01*
X548973Y-339245D02*
X555003Y-345276D01*
X594882Y-234566D02*
Y-165748D01*
X605301Y-345276D02*
X606784Y-343792D01*
X555003Y-345276D02*
X605301D01*
X606784Y-343792D02*
Y-330425D01*
X613267Y-323942D02*
Y-263386D01*
X606784Y-330425D02*
X613267Y-323942D01*
X608542Y-258661D02*
X613267Y-263386D01*
X604331Y-258661D02*
X608542D01*
X602283Y-256614D02*
Y-241968D01*
Y-256614D02*
X604331Y-258661D01*
X594882Y-234566D02*
X602283Y-241968D01*
X551850Y-346731D02*
X605683D01*
X597441Y-232641D02*
Y-170669D01*
X605683Y-346731D02*
X608491Y-343924D01*
Y-330557D01*
X614567Y-324481D01*
X597441Y-232641D02*
X607809Y-243009D01*
Y-255426D02*
Y-243009D01*
Y-255426D02*
X614567Y-262184D01*
Y-324481D02*
Y-262184D01*
X434252Y-348031D02*
X602712D01*
X598819Y-228404D02*
Y-170079D01*
X602712Y-348031D02*
X602887Y-348207D01*
X606046D02*
X609803Y-344450D01*
X602887Y-348207D02*
X606046D01*
X618532Y-322544D02*
X625353Y-315723D01*
X618342Y-322544D02*
X618532D01*
X609803Y-331083D02*
X618342Y-322544D01*
X609803Y-344450D02*
Y-331083D01*
X622449Y-259961D02*
X625353Y-262865D01*
Y-315723D02*
Y-262865D01*
X614183Y-259961D02*
X622449D01*
X609109Y-254888D02*
X614183Y-259961D01*
X609109Y-254888D02*
Y-238694D01*
X598819Y-228404D02*
X609109Y-238694D01*
X432558Y-349487D02*
X602329D01*
X601181Y-228928D02*
Y-170472D01*
X602329Y-349487D02*
X602349Y-349507D01*
X606628D02*
X611298Y-344836D01*
X602349Y-349507D02*
X606628D01*
X601181Y-228928D02*
X610409Y-238156D01*
Y-254349D02*
X614721Y-258661D01*
X623228D01*
X619070Y-323844D02*
X626653Y-316261D01*
X623228Y-258661D02*
X626653Y-262086D01*
X610409Y-254349D02*
Y-238156D01*
X626653Y-316261D02*
Y-262086D01*
X611298Y-331426D02*
X618881Y-323844D01*
X611298Y-344836D02*
Y-331426D01*
X618881Y-323844D02*
X619070D01*
X431496Y-350787D02*
X601791D01*
X601811Y-350807D02*
X607166D01*
X601791Y-350787D02*
X601811Y-350807D01*
X612180Y-254282D02*
Y-236778D01*
X613067Y-331496D02*
X613256D01*
X612598Y-331965D02*
X613067Y-331496D01*
X612598Y-345375D02*
Y-331965D01*
X607166Y-350807D02*
X612598Y-345375D01*
X613256Y-331496D02*
X627953Y-316800D01*
X623622Y-257087D02*
X627953Y-261417D01*
Y-316800D02*
Y-261417D01*
X612180Y-254282D02*
X614985Y-257087D01*
X623622D01*
X603937Y-228535D02*
X612180Y-236778D01*
X286521Y-169093D02*
X315624D01*
X388189Y-167323D02*
Y-162205D01*
X383625Y-171887D02*
X388189Y-167323D01*
X358895Y-171887D02*
X383625D01*
X350305Y-163297D02*
X358895Y-171887D01*
X339448Y-163297D02*
X350305D01*
X336603Y-166142D02*
X339448Y-163297D01*
X328346Y-166142D02*
X336603D01*
X325501Y-163297D02*
X328346Y-166142D01*
X321421Y-163297D02*
X325501D01*
X315624Y-169093D02*
X321421Y-163297D01*
X360336Y-170572D02*
X377998D01*
X320670Y-161417D02*
X351181D01*
X360336Y-170572D01*
X314512Y-167575D02*
X320670Y-161417D01*
X288835Y-167575D02*
X314512D01*
X252619Y-156819D02*
X274247D01*
X286521Y-169093D01*
X276772Y-155512D02*
X288835Y-167575D01*
X253150Y-155512D02*
X276772D01*
X223681Y-133039D02*
X241732Y-114987D01*
X241894D02*
X243426Y-113455D01*
X241732Y-114987D02*
X241894D01*
X243426Y-113455D02*
X248430D01*
X249739Y-114764D01*
Y-153939D02*
Y-114764D01*
Y-153939D02*
X252619Y-156819D01*
X225747Y-129134D02*
X242726Y-112155D01*
X248968D01*
X251039Y-114225D01*
Y-153401D02*
Y-114225D01*
X178931Y-130512D02*
X183538D01*
X186065Y-133039D01*
X223681D01*
X174386Y-135057D02*
X178931Y-130512D01*
X170311Y-139961D02*
X170437Y-140086D01*
X173378D01*
X174386Y-139078D01*
Y-135057D01*
X383083Y-165488D02*
Y-161839D01*
X377998Y-170572D02*
X383083Y-165488D01*
X284646Y-170472D02*
X316929D01*
X321260Y-166142D01*
X251039Y-153401D02*
X253150Y-155512D01*
X172674Y-133625D02*
X177165Y-129134D01*
X225747D01*
X172674Y-138386D02*
Y-133625D01*
X252953Y-159605D02*
X273778D01*
X284646Y-170472D01*
X248031Y-154683D02*
X252953Y-159605D01*
X248031Y-154683D02*
Y-118504D01*
X245276Y-115748D02*
X248031Y-118504D01*
X272483Y-161460D02*
X282896Y-171872D01*
X271172Y-161460D02*
X272483D01*
X231475Y-142401D02*
X249979Y-160905D01*
X270617D01*
X271172Y-161460D01*
X184765Y-142401D02*
X231475D01*
X172441Y-154724D02*
X184765Y-142401D01*
X82761Y-136224D02*
X126307D01*
X82213Y-135677D02*
X82761Y-136224D01*
X71202Y-138095D02*
X73620Y-135677D01*
X82213D01*
X129063Y-136618D02*
Y-136576D01*
X126618Y-134130D02*
X129063Y-136576D01*
X72212Y-134130D02*
X126618D01*
X68889Y-137453D02*
X72212Y-134130D01*
X69558Y-139739D02*
X71202Y-138095D01*
X67398Y-139739D02*
X69558D01*
X66929Y-139270D02*
X67398Y-139739D01*
X66929Y-139270D02*
Y-75590D01*
X38583Y-58355D02*
X49694D01*
X66929Y-75590D01*
X68889Y-137453D02*
Y-74401D01*
X47844Y-53355D02*
X68889Y-74401D01*
X38613Y-53355D02*
X47844D01*
X58718Y-147363D02*
X168847D01*
X51287Y-139931D02*
Y-126878D01*
Y-139931D02*
X58718Y-147363D01*
X392133Y-191739D02*
X422047Y-221654D01*
X384646Y-189412D02*
Y-184252D01*
X386973Y-191739D02*
X392133D01*
X384646Y-189412D02*
X386973Y-191739D01*
X377038Y-176506D02*
X390679D01*
X394918Y-189012D02*
X399213Y-193307D01*
X390679Y-176506D02*
X394918Y-180744D01*
Y-189012D02*
Y-180744D01*
X414961Y-246457D02*
X427291Y-258787D01*
X385541Y-223820D02*
X392596Y-230875D01*
Y-238981D02*
X400071Y-246457D01*
X414961D01*
X392596Y-238981D02*
Y-230875D01*
X170359Y-109756D02*
X204193D01*
X210255Y-103695D02*
X211648D01*
X204193Y-109756D02*
X210255Y-103695D01*
X49587Y-93723D02*
Y-68345D01*
X50394Y-150000D02*
X88189D01*
X40157Y-139764D02*
Y-103153D01*
X49587Y-93723D01*
X40157Y-139764D02*
X50394Y-150000D01*
X38627Y-144532D02*
Y-99169D01*
Y-144532D02*
X46063Y-151969D01*
X47190Y-90606D02*
Y-68449D01*
X46063Y-151969D02*
X85433D01*
X38627Y-99169D02*
X47190Y-90606D01*
X41339Y-88315D02*
Y-65354D01*
X26378Y-143353D02*
X53891Y-170866D01*
X26378Y-143353D02*
Y-103276D01*
X41339Y-88315D01*
X38189Y-86603D02*
Y-67716D01*
X24016Y-145034D02*
X51423Y-172441D01*
X24016Y-100776D02*
X38189Y-86603D01*
X24016Y-145034D02*
Y-100776D01*
X41872Y-60630D02*
X49587Y-68345D01*
X40670Y-61930D02*
X47190Y-68449D01*
X28259Y-61724D02*
X32677Y-66142D01*
X22047Y-52626D02*
Y10512D01*
X28259Y-61724D02*
Y-58838D01*
X22047Y-52626D02*
X28259Y-58838D01*
X312868Y-155636D02*
X313386Y-155118D01*
X312868Y-156299D02*
X317828Y-161260D01*
X312868Y-156299D02*
Y-155636D01*
X313386Y-155118D02*
Y-93701D01*
X311536Y-159255D02*
Y-157599D01*
X310630Y-156693D02*
X311536Y-157599D01*
X310630Y-156693D02*
Y-95276D01*
X311536Y-159255D02*
X313878Y-161597D01*
X594882Y-165748D02*
X601968Y-158661D01*
X159784Y-99181D02*
X170359Y-109756D01*
X162986Y-87795D02*
X177559D01*
X158661Y-92120D02*
X162986Y-87795D01*
X158661Y-95289D02*
Y-92120D01*
X159784Y-99181D02*
Y-96412D01*
X158661Y-95289D02*
X159784Y-96412D01*
X337980Y-290788D02*
X355748D01*
X280414Y-287478D02*
X300762D01*
X333102Y-285910D02*
X337980Y-290788D01*
X302330Y-285910D02*
X333102D01*
X300762Y-287478D02*
X302330Y-285910D01*
X287258Y-294345D02*
X305464D01*
X284646Y-291732D02*
X287258Y-294345D01*
X422047Y-248425D02*
Y-221654D01*
X396995Y-158543D02*
X397376Y-158923D01*
X386379Y-158543D02*
X396995D01*
X397376Y-158923D02*
Y-158923D01*
X383083Y-161839D02*
X386379Y-158543D01*
X413237Y-174784D02*
X421313D01*
X397376Y-158923D02*
X413237Y-174784D01*
X387427Y-159843D02*
X396457D01*
X387427Y-161226D02*
X388189Y-161988D01*
Y-162205D02*
Y-161988D01*
X387427Y-161226D02*
Y-159843D01*
X413359Y-176745D02*
X419798D01*
X396457Y-159843D02*
X413359Y-176745D01*
X415717Y-158475D02*
X420115Y-162873D01*
X423666D02*
X426103Y-165310D01*
X420115Y-162873D02*
X423666D01*
X408081Y-158475D02*
X415717D01*
X426103Y-168862D02*
Y-165310D01*
X428551Y-172382D02*
Y-171310D01*
X426103Y-168862D02*
X428551Y-171310D01*
X426378Y-214961D02*
X432677Y-208661D01*
Y-176508D01*
X428551Y-172382D02*
X432677Y-176508D01*
X399213Y-149606D02*
X408081Y-158475D01*
X378346Y-149606D02*
X399213D01*
X353937Y-125197D02*
X378346Y-149606D01*
X424922Y-212479D02*
X430328Y-207074D01*
X424803Y-170472D02*
X430328Y-175997D01*
Y-207074D02*
Y-175997D01*
X424803Y-170472D02*
Y-165849D01*
X423128Y-164173D02*
X424803Y-165849D01*
X419450Y-164173D02*
X423128D01*
X415052Y-159775D02*
X419450Y-164173D01*
X407413Y-159775D02*
X415052D01*
X398819Y-151181D02*
X407413Y-159775D01*
X351575Y-125591D02*
X377145Y-151161D01*
X398788Y-151181D02*
X398819D01*
X398768Y-151161D02*
X398788Y-151181D01*
X377145Y-151161D02*
X398768D01*
X427521Y-181890D02*
X429028Y-180383D01*
X375689Y-152461D02*
X398229D01*
X324016Y-100787D02*
X375689Y-152461D01*
X398229D02*
X414911Y-169142D01*
X421204D01*
X429028Y-176967D01*
Y-180383D02*
Y-176967D01*
X543307Y-236221D02*
X550394Y-243307D01*
X550391Y-243310D02*
X550394Y-243307D01*
X481890Y-236221D02*
X543307D01*
X477165Y-240945D02*
X481890Y-236221D01*
X477165Y-247244D02*
Y-240945D01*
X459689Y-233311D02*
X561571D01*
X458661Y-232283D02*
X459689Y-233311D01*
X561571D02*
X562992Y-231890D01*
X22047Y10512D02*
X26889Y15354D01*
X35433D01*
X426378Y-225197D02*
X428740Y-227559D01*
X426378Y-225197D02*
Y-214961D01*
X424922Y-226497D02*
X427521Y-229096D01*
X424922Y-226497D02*
Y-212479D01*
X423622Y-210567D02*
X427921Y-206268D01*
X423622Y-232677D02*
Y-210567D01*
Y-232677D02*
X438583Y-247638D01*
X441942Y-231083D02*
X443142Y-232283D01*
X428740Y-227559D02*
X436484D01*
X440008Y-231083D02*
X441942D01*
X436484Y-227559D02*
X440008Y-231083D01*
X427521Y-229096D02*
X436182D01*
X429528Y-231496D02*
X433328Y-235296D01*
X438326D02*
X444369Y-241339D01*
X433328Y-235296D02*
X438326D01*
X436182Y-229096D02*
X446457Y-239370D01*
X462205Y-255118D02*
Y-252296D01*
X457547Y-247638D02*
X462205Y-252296D01*
X353937Y-125197D02*
Y-116142D01*
X347244Y-109449D02*
X353937Y-116142D01*
X345276Y-109449D02*
X347244D01*
X351575Y-125591D02*
Y-120784D01*
X348508Y-117717D02*
X351575Y-120784D01*
X344882Y-117717D02*
X348508D01*
X339370Y-112205D02*
X344882Y-117717D01*
X339370Y-112205D02*
Y-108268D01*
X245669Y-14567D02*
X339370Y-108268D01*
X324016Y-100787D02*
Y-95669D01*
X247244Y-18898D02*
X324016Y-95669D01*
X319685Y-98938D02*
X374658Y-153911D01*
X319685Y-98938D02*
Y-96063D01*
X255906Y-44094D02*
X309330Y-97519D01*
X210236Y-44094D02*
X255906D01*
X309330Y-157231D02*
Y-97519D01*
X215354Y-42126D02*
X257480D01*
X310630Y-95276D01*
X259449Y-39764D02*
X313386Y-93701D01*
X220866Y-39764D02*
X259449D01*
X247119Y-23497D02*
X319685Y-96063D01*
X186837Y-23497D02*
X247119D01*
X188976Y-18898D02*
X247244D01*
X197244Y-14567D02*
X245669D01*
X221510Y14317D02*
Y19810D01*
Y14317D02*
X345276Y-109449D01*
X171536Y-8196D02*
X186837Y-23497D01*
X310236Y-165748D02*
Y-158138D01*
X309330Y-157231D02*
X310236Y-158138D01*
X188189Y-44094D02*
X210236D01*
X582165Y-153661D02*
X591339Y-144488D01*
X582165Y-163898D02*
Y-153661D01*
X576700Y-169363D02*
X582165Y-163898D01*
X575724Y-169363D02*
X576700D01*
X443142Y-232283D02*
X458661D01*
X562992Y-231890D02*
Y-224016D01*
X571654Y-215354D01*
Y-173433D01*
X575724Y-169363D01*
X150477Y19810D02*
X221510D01*
X465896Y-247883D02*
X467381Y-246398D01*
Y-244247D01*
X462504Y-239370D02*
X467381Y-244247D01*
X446457Y-239370D02*
X462504D01*
X169291Y13386D02*
X197244Y-14567D01*
X171653Y-1575D02*
X188976Y-18898D01*
X165354Y-1575D02*
X171653D01*
X155905Y7874D02*
X165354Y-1575D01*
X155905Y7874D02*
Y13386D01*
X151181Y18110D02*
X155905Y13386D01*
X34574Y-230637D02*
X36614Y-232677D01*
X33420Y-229641D02*
X34416Y-230637D01*
X34574D01*
X29528Y-225591D02*
Y-195229D01*
X22095Y-187797D02*
X29528Y-195229D01*
Y-225591D02*
X33420Y-229483D01*
Y-229641D02*
Y-229483D01*
X421374Y-172441D02*
X423996Y-175063D01*
Y-176752D02*
Y-175063D01*
Y-176752D02*
X426772Y-179528D01*
X444369Y-241339D02*
X460270D01*
X601968Y-158661D02*
Y-99109D01*
Y-98973D02*
Y-98425D01*
Y-98973D02*
X602105Y-99109D01*
X597244Y-108661D02*
X599105Y-110522D01*
X592913Y-116535D02*
X597244Y-120866D01*
X599105Y-158837D02*
Y-110522D01*
X590551Y-167390D02*
X599105Y-158837D01*
X590551Y-170472D02*
Y-167390D01*
X597244Y-157090D02*
Y-120866D01*
X588189Y-166145D02*
X597244Y-157090D01*
X588189Y-170965D02*
Y-166145D01*
X594488Y-156693D02*
Y-132677D01*
X574803Y-176378D02*
X594488Y-156693D01*
X614567Y-133071D02*
X619449Y-128189D01*
X614567Y-151575D02*
Y-133071D01*
X597519Y-168623D02*
X614567Y-151575D01*
X597519Y-170591D02*
Y-168623D01*
X597441Y-170669D02*
X597519Y-170591D01*
X623622Y-149606D02*
Y-122362D01*
X619449Y-118189D02*
X623622Y-122362D01*
X619211Y-154017D02*
X623622Y-149606D01*
X614881Y-154017D02*
X619211D01*
X598819Y-170079D02*
X614881Y-154017D01*
X625591Y-150477D02*
Y-114331D01*
X619449Y-108189D02*
X625591Y-114331D01*
X620070Y-155998D02*
X625591Y-150477D01*
X615656Y-155998D02*
X620070D01*
X601181Y-170472D02*
X615656Y-155998D01*
X627165Y-151575D02*
Y-105905D01*
X619449Y-98189D02*
X627165Y-105905D01*
X619685Y-159055D02*
X627165Y-151575D01*
X615748Y-159055D02*
X619685D01*
X603937Y-170866D02*
X615748Y-159055D01*
X574803Y-216535D02*
Y-176378D01*
X544772Y-327559D02*
X557087Y-315245D01*
X533873Y-327559D02*
X544772D01*
X521943Y-339489D02*
X533873Y-327559D01*
X495395Y-339489D02*
X521943D01*
X494095Y-338189D02*
X495395Y-339489D01*
X494095Y-338189D02*
Y-319685D01*
X486477Y-312067D02*
X494095Y-319685D01*
X471791Y-312067D02*
X486477D01*
X469291Y-314567D02*
X471791Y-312067D01*
X424241Y-314567D02*
X469291D01*
X414005Y-304331D02*
X424241Y-314567D01*
X346989Y-304331D02*
X414005D01*
X280836Y-306820D02*
X344500D01*
X346989Y-304331D01*
X275883Y-301867D02*
X280836Y-306820D01*
X275883Y-301867D02*
Y-265564D01*
X497638Y-337327D02*
X498500Y-338189D01*
X515354D01*
X535772Y-317771D01*
X497638Y-337327D02*
Y-316629D01*
X263743Y-253424D02*
X275883Y-265564D01*
X258941Y-253424D02*
X263743D01*
X256298Y-250782D02*
X258941Y-253424D01*
X253450Y-250782D02*
X256298D01*
X251322Y-248655D02*
X253450Y-250782D01*
X243996Y-248655D02*
X251322D01*
X576632Y-182522D02*
X588189Y-170965D01*
X539784Y-335976D02*
X548814Y-326946D01*
X528490Y-335976D02*
X539784D01*
X525368Y-339099D02*
X528490Y-335976D01*
X525368Y-340765D02*
Y-339099D01*
X524014Y-342118D02*
X525368Y-340765D01*
X493307Y-342118D02*
X524014D01*
X491732Y-340544D02*
X493307Y-342118D01*
X491732Y-340544D02*
Y-321755D01*
X484938Y-314961D02*
X491732Y-321755D01*
X482458Y-314961D02*
X484938D01*
X478988Y-318431D02*
X482458Y-314961D01*
X450073Y-318431D02*
X478988D01*
X441339Y-327165D02*
X450073Y-318431D01*
X421260Y-327165D02*
X441339D01*
X400263Y-306169D02*
X421260Y-327165D01*
X362193Y-306169D02*
X400263D01*
X360242Y-308120D02*
X362193Y-306169D01*
X273474Y-307651D02*
X273943Y-308120D01*
X360242D01*
X273474Y-307651D02*
Y-266013D01*
X266238Y-258777D02*
X273474Y-266013D01*
X262321Y-258777D02*
X266238D01*
X261024Y-257480D02*
X262321Y-258777D01*
X261024Y-257480D02*
Y-256388D01*
X259360Y-254724D02*
X261024Y-256388D01*
X258104Y-254724D02*
X259360D01*
X257710Y-255118D02*
X258104Y-254724D01*
X256365Y-255118D02*
X257710D01*
X254119Y-252871D02*
X256365Y-255118D01*
X250059Y-252871D02*
X254119D01*
X247995Y-250808D02*
X250059Y-252871D01*
X246118Y-250808D02*
X247995D01*
X245965Y-250655D02*
X246118Y-250808D01*
X272778Y-310117D02*
X360091D01*
X590551Y-170472D02*
X590686Y-170607D01*
Y-182149D02*
Y-170607D01*
X588287Y-184547D02*
X590686Y-182149D01*
X588287Y-193602D02*
Y-184547D01*
X585132Y-196757D02*
X588287Y-193602D01*
X540322Y-337276D02*
X548674Y-328925D01*
X529029Y-337276D02*
X540322D01*
X526917Y-339388D02*
X529029Y-337276D01*
X524553Y-343418D02*
X526917Y-341054D01*
Y-339388D01*
X435544Y-343418D02*
X524553D01*
X400000Y-307874D02*
X435544Y-343418D01*
X362335Y-307874D02*
X400000D01*
X360091Y-310117D02*
X362335Y-307874D01*
X272105Y-309445D02*
X272778Y-310117D01*
X272105Y-309445D02*
Y-267832D01*
X264509Y-260236D02*
X272105Y-267832D01*
X258480Y-260236D02*
X264509D01*
X252744Y-254500D02*
X258480Y-260236D01*
X249019Y-254500D02*
X252744D01*
X247110Y-252592D02*
X249019Y-254500D01*
X243996Y-252592D02*
X247110D01*
X259340Y-251887D02*
X272481D01*
X254162Y-246709D02*
X259340Y-251887D01*
X238996Y-246709D02*
X254162D01*
X538512Y-339245D02*
X548973D01*
X536615Y-341142D02*
X538512Y-339245D01*
X529461Y-341142D02*
X536615D01*
X525884Y-344718D02*
X529461Y-341142D01*
X434616Y-344718D02*
X525884D01*
X399339Y-309442D02*
X434616Y-344718D01*
X245965Y-254655D02*
X248507Y-257197D01*
X257742Y-261692D02*
X263817D01*
X253247Y-257197D02*
X257742Y-261692D01*
X263817D02*
X270564Y-268440D01*
X271033Y-311417D02*
X360630D01*
X270564Y-310949D02*
Y-268440D01*
Y-310949D02*
X271033Y-311417D01*
X248507Y-257197D02*
X253247D01*
X360630Y-311417D02*
X362605Y-309442D01*
X399339D01*
X460407Y-308482D02*
X491356D01*
X453501Y-301575D02*
X460407Y-308482D01*
X356742Y-301575D02*
X453501D01*
X352018Y-296850D02*
X356742Y-301575D01*
X307969Y-296850D02*
X352018D01*
X305464Y-294345D02*
X307969Y-296850D01*
X548389Y-343271D02*
X551850Y-346731D01*
X529170Y-343271D02*
X548389D01*
X526423Y-346018D02*
X529170Y-343271D01*
X434077Y-346018D02*
X526423D01*
X398801Y-310742D02*
X434077Y-346018D01*
X363791Y-310742D02*
X398801D01*
X361191Y-313342D02*
X363791Y-310742D01*
X331678Y-313342D02*
X361191D01*
X331678Y-313342D02*
X331678Y-313342D01*
X299616Y-313342D02*
X331678D01*
X269264Y-312890D02*
X269733Y-313358D01*
X269264Y-312890D02*
Y-268978D01*
X269733Y-313358D02*
X299600D01*
X299616Y-313342D01*
X263278Y-262992D02*
X269264Y-268978D01*
X256901Y-262992D02*
X263278D01*
X252406Y-258497D02*
X256901Y-262992D01*
X244028Y-258497D02*
X252406D01*
X398263Y-312042D02*
X434252Y-348031D01*
X364730Y-312042D02*
X398263D01*
X359985Y-316787D02*
X364730Y-312042D01*
X270799Y-316787D02*
X359985D01*
X267964Y-313952D02*
X270799Y-316787D01*
X267964Y-313952D02*
Y-273290D01*
X263178Y-268504D02*
X267964Y-273290D01*
X259943Y-268504D02*
X263178D01*
X251412Y-260497D02*
X252080Y-261166D01*
X252605D01*
X259943Y-268504D01*
X245965Y-260497D02*
X251412D01*
X396413Y-313342D02*
X432558Y-349487D01*
X368376Y-313342D02*
X396413D01*
X363004Y-318714D02*
X368376Y-313342D01*
X269895Y-318714D02*
X363004D01*
X266317Y-315136D02*
X269895Y-318714D01*
X266317Y-315136D02*
Y-274584D01*
X261705Y-269972D02*
X266317Y-274584D01*
X259048Y-269972D02*
X261705D01*
X251541Y-262466D02*
X259048Y-269972D01*
X244028Y-262466D02*
X251541D01*
X603937Y-228535D02*
Y-170866D01*
X398031Y-317323D02*
X431496Y-350787D01*
X367028Y-317323D02*
X398031D01*
X363956Y-320395D02*
X367028Y-317323D01*
X269608Y-320395D02*
X363956D01*
X265017Y-315805D02*
X269608Y-320395D01*
X265017Y-315805D02*
Y-282687D01*
X261024Y-278694D02*
X265017Y-282687D01*
X261024Y-278694D02*
Y-274016D01*
X251505Y-264497D02*
X261024Y-274016D01*
X245965Y-264497D02*
X251505D01*
X159449Y-303937D02*
X252009D01*
X257874Y-298072D01*
Y-291732D01*
X260630Y-288976D01*
Y-281102D01*
X256217Y-276690D02*
X260630Y-281102D01*
X256217Y-276690D02*
Y-273228D01*
X251886Y-268898D02*
X256217Y-273228D01*
X236614Y-268898D02*
X251886D01*
X234252Y-266535D02*
X236614Y-268898D01*
X234252Y-266535D02*
Y-251453D01*
X238996Y-246709D01*
X272481Y-251887D02*
X276672Y-256078D01*
X331323D01*
X256090Y-295415D02*
Y-278982D01*
X248149Y-271041D02*
X256090Y-278982D01*
X233246Y-271041D02*
X248149D01*
X232283Y-270079D02*
X233246Y-271041D01*
X232283Y-270079D02*
Y-250000D01*
X237970Y-244314D01*
X254065D01*
X259194Y-249443D01*
X250059Y-285783D02*
Y-276979D01*
X247095Y-274016D02*
X250059Y-276979D01*
X230709Y-274016D02*
X247095D01*
X224410Y-267717D02*
X230709Y-274016D01*
X224410Y-267717D02*
Y-251969D01*
X235317Y-241060D01*
X270851D01*
X274719Y-244928D01*
X273575Y-241339D02*
X283071D01*
X123524Y-311024D02*
X187743Y-246804D01*
X205307D01*
X214419Y-237693D01*
X231435D02*
X232540Y-238798D01*
X271034D01*
X214419Y-237693D02*
X231435D01*
X271034Y-238798D02*
X273575Y-241339D01*
X160702Y-247172D02*
X183930D01*
X274731Y-238723D02*
X279989D01*
X183930Y-247172D02*
X201969Y-229134D01*
X231713D01*
X236751Y-234171D01*
X270180D01*
X274731Y-238723D01*
X158268Y-244882D02*
X182283D01*
X199739Y-227426D01*
X249765D01*
X254850Y-232511D01*
X273456D01*
X277165Y-236221D01*
X176104Y-229134D02*
X183978Y-221260D01*
X160617Y-229134D02*
X176104D01*
X167054Y-230977D02*
X178825D01*
X185367Y-224435D01*
X251560D01*
X257440Y-230315D01*
X279134D01*
X183978Y-221260D02*
X275197D01*
X280315Y-226378D01*
X157087Y-301181D02*
X250325D01*
X294258Y-249443D02*
X323228Y-220472D01*
X250325Y-301181D02*
X256090Y-295415D01*
X259194Y-249443D02*
X294258D01*
X245290Y-290551D02*
X250059Y-285783D01*
X25197Y-53937D02*
Y-48819D01*
X32972Y5020D02*
X36220Y8268D01*
X32972Y-2316D02*
Y5020D01*
Y-2316D02*
X39370Y-8714D01*
Y-22835D02*
Y-8714D01*
X37795Y-24409D02*
X39370Y-22835D01*
X37795Y-32283D02*
Y-24409D01*
X27559Y-42520D02*
X37795Y-32283D01*
X27559Y-46457D02*
Y-42520D01*
X25197Y-48819D02*
X27559Y-46457D01*
X35827Y1575D02*
X38878D01*
X43307Y-2854D01*
Y-29921D02*
Y-2854D01*
X29528Y-43701D02*
X43307Y-29921D01*
X29528Y-55237D02*
Y-43701D01*
X33465Y-43701D02*
X37916Y-39250D01*
X39097D02*
X43701Y-34646D01*
X37916Y-39250D02*
X39097D01*
X25197Y-53937D02*
X34646Y-63386D01*
X51423Y-172441D02*
X165748D01*
X32677Y-66142D02*
X36614D01*
X38189Y-67716D01*
X53891Y-170866D02*
X164961D01*
X34646Y-63386D02*
X39370D01*
X41339Y-65354D01*
X29528Y-55237D02*
X36220Y-61930D01*
X40670D01*
X33465Y-55641D02*
Y-43701D01*
Y-55641D02*
X38453Y-60630D01*
X41872D01*
X14961Y-166142D02*
Y-154756D01*
X13386Y-153182D02*
Y-126878D01*
Y-153182D02*
X14961Y-154756D01*
X88189Y-150000D02*
X92913Y-154724D01*
X172441D01*
X175197Y-157087D02*
X188583Y-143701D01*
X230937D01*
X90551Y-157087D02*
X175197D01*
X85433Y-151969D02*
X90551Y-157087D01*
X168847Y-147363D02*
X175764Y-140446D01*
X164961Y-170866D02*
X188976Y-146850D01*
X231615D01*
X165748Y-172441D02*
X188253Y-149936D01*
X166425Y-174913D02*
X186505Y-154834D01*
X11511Y-174913D02*
X166425D01*
X4724Y-181700D02*
X11511Y-174913D01*
X167861Y-177021D02*
X186656Y-158226D01*
X12349Y-177021D02*
X167861D01*
X6693Y-182677D02*
X12349Y-177021D01*
X12205Y-183465D02*
X12623Y-183046D01*
X245669Y-181496D02*
X251969Y-187795D01*
X33858Y-181496D02*
X245669D01*
X32308Y-183046D02*
X33858Y-181496D01*
X12623Y-183046D02*
X32308D01*
X282896Y-171872D02*
X343237D01*
X345251Y-173886D02*
X357213D01*
X343237Y-171872D02*
X345251Y-173886D01*
X357213D02*
X363401Y-180073D01*
Y-185025D02*
Y-180073D01*
X360898Y-187527D02*
X363401Y-185025D01*
X360898Y-199875D02*
Y-187527D01*
Y-199875D02*
X361780Y-200757D01*
X361417Y-219001D02*
X361780Y-218638D01*
Y-200757D01*
X361417Y-260630D02*
Y-219001D01*
Y-260630D02*
X374016Y-273228D01*
X417717D01*
X427739Y-283251D01*
X432579D01*
X230937Y-143701D02*
X249441Y-162205D01*
X270079D01*
X281046Y-173172D01*
X342698D01*
X345051Y-175525D01*
X349041D01*
X352362Y-178846D01*
Y-182283D02*
Y-178846D01*
Y-182283D02*
X359143Y-189064D01*
Y-209182D02*
X360480Y-210520D01*
X359143Y-209182D02*
Y-189064D01*
X358661Y-219919D02*
X360480Y-218100D01*
Y-210520D01*
X358661Y-265354D02*
Y-219919D01*
Y-265354D02*
X368379Y-275072D01*
X390820D01*
X392126Y-276378D01*
X416904D01*
X426927Y-286400D01*
X432579D01*
X279619Y-174631D02*
X333253D01*
X333426Y-174803D01*
X249213Y-164448D02*
X269436D01*
X279619Y-174631D01*
X333426Y-174803D02*
X342491D01*
X268898Y-165748D02*
X279080Y-175931D01*
X332715D02*
X333632Y-176848D01*
X279080Y-175931D02*
X332715D01*
X319769Y-177417D02*
X325063D01*
X318773Y-178413D02*
X319769Y-177417D01*
X325063D02*
X326705Y-179059D01*
X231615Y-146850D02*
X249213Y-164448D01*
X342491Y-174803D02*
X346876Y-179188D01*
Y-184671D02*
X349216Y-187011D01*
X346876Y-184671D02*
Y-179188D01*
X349216Y-187011D02*
X355170D01*
X357080Y-188922D01*
Y-189167D02*
Y-188922D01*
Y-189167D02*
X357843Y-189929D01*
Y-211386D02*
Y-189929D01*
Y-211386D02*
X359180Y-212724D01*
Y-216017D02*
Y-212724D01*
X357101Y-218096D02*
X359180Y-216017D01*
X357101Y-267467D02*
Y-218096D01*
Y-267467D02*
X371523Y-281890D01*
X399564D01*
X402320Y-279134D02*
X409901D01*
X399564Y-281890D02*
X402320Y-279134D01*
X412263Y-281496D02*
X419408D01*
X409901Y-279134D02*
X412263Y-281496D01*
X419408D02*
X427269Y-289358D01*
X432720D01*
X175764Y-140446D02*
Y-136083D01*
X178185Y-133661D01*
X188253Y-149936D02*
X232820D01*
X248632Y-165748D01*
X268898D01*
X333632Y-176848D02*
X341742D01*
X343307Y-178413D01*
Y-180667D02*
Y-178413D01*
X342281Y-181693D02*
X343307Y-180667D01*
X342281Y-183620D02*
Y-181693D01*
Y-183620D02*
X347653Y-188992D01*
X355312D01*
X355780Y-189460D01*
Y-267985D02*
Y-189460D01*
Y-267985D02*
X371260Y-283465D01*
X418042D01*
X426332Y-291755D01*
X432835D01*
X27067Y-298727D02*
X109148D01*
X160702Y-247172D01*
X73622Y-293701D02*
X109449D01*
X158268Y-244882D01*
X136221Y-261811D02*
X167054Y-230977D01*
X30355Y-285867D02*
Y-255158D01*
X18504Y-243307D02*
X30355Y-255158D01*
X7582Y-243307D02*
X18504D01*
X2756Y-238481D02*
Y-235103D01*
Y-238481D02*
X7582Y-243307D01*
X2756Y-235103D02*
X9102Y-228757D01*
Y-200436D01*
X7471Y-198805D02*
X9102Y-200436D01*
X7471Y-198805D02*
Y-195672D01*
X2697Y-190899D02*
X7471Y-195672D01*
X2697Y-190899D02*
Y-178405D01*
X14961Y-166142D01*
X35039Y-285827D02*
Y-251181D01*
X4724Y-188841D02*
Y-181700D01*
X24928Y-241070D02*
X35039Y-251181D01*
X18462Y-240551D02*
X18981Y-241070D01*
X24928D01*
X11166Y-240551D02*
X18462D01*
X7701Y-237086D02*
X11166Y-240551D01*
X7701Y-237086D02*
Y-233071D01*
X9276Y-231496D01*
X21260D01*
X23622Y-229134D01*
Y-199805D01*
X21849Y-198031D02*
X23622Y-199805D01*
X13938Y-198031D02*
X21849D01*
X4747Y-188841D02*
X13938Y-198031D01*
X4724Y-188841D02*
X4747D01*
X6693Y-188243D02*
Y-182677D01*
X21985Y-194882D02*
X25984Y-198881D01*
X13943Y-194882D02*
X21985D01*
X7304Y-188243D02*
X13943Y-194882D01*
X6693Y-188243D02*
X7304D01*
X8143Y-186678D02*
Y-184452D01*
X9261Y-187797D02*
X22095D01*
X8143Y-186678D02*
X9261Y-187797D01*
X9130Y-183465D02*
X12205D01*
X8143Y-184452D02*
X9130Y-183465D01*
X29684Y-292655D02*
X36425D01*
X37905Y-291175D02*
Y-287795D01*
X36425Y-292655D02*
X37905Y-291175D01*
X32283Y-287795D02*
X37905D01*
X30355Y-285867D02*
X32283Y-287795D01*
X7563Y-287402D02*
X27043D01*
X29602Y-289961D01*
X35039D01*
X19488Y-292126D02*
X23425Y-296063D01*
X71260D02*
X73622Y-293701D01*
X23425Y-296063D02*
X71260D01*
X26851Y-289822D02*
X29684Y-292655D01*
X8928Y-289822D02*
X26851D01*
X7480Y-291269D02*
X8928Y-289822D01*
X7480Y-295107D02*
Y-291269D01*
Y-295107D02*
X17717Y-305343D01*
Y-339370D02*
Y-305343D01*
Y-339370D02*
X18904Y-340558D01*
X27946D01*
X34252Y-334252D01*
X103937D01*
X99805Y-343108D02*
X152362Y-290551D01*
X19341Y-344488D02*
X20720Y-343108D01*
X99805D01*
X24493Y-351969D02*
X106299D01*
X22146Y-349622D02*
X24493Y-351969D01*
X22146Y-349622D02*
Y-347466D01*
X24397Y-345214D01*
X29543D01*
X103937Y-334252D02*
X159449Y-278740D01*
X240158D01*
X5709Y-297047D02*
Y-289256D01*
X7563Y-287402D01*
X318773Y-178865D02*
Y-178413D01*
X313799Y-183839D02*
X318773Y-178865D01*
X303319Y-183839D02*
X313799D01*
X297040Y-177559D02*
X303319Y-183839D01*
X277953Y-177559D02*
X297040D01*
X269487Y-169093D02*
X277953Y-177559D01*
X248514Y-169093D02*
X269487D01*
X233358Y-153937D02*
X248514Y-169093D01*
X201575Y-153937D02*
X233358D01*
X186505Y-154834D02*
X200678D01*
X201575Y-153937D01*
X319971Y-181496D02*
X324476D01*
X315640Y-185827D02*
X319971Y-181496D01*
X302756Y-185827D02*
X315640D01*
X296063Y-179134D02*
X302756Y-185827D01*
X269645Y-179134D02*
X296063D01*
X263346Y-185433D02*
X269645Y-179134D01*
X252362Y-185433D02*
X263346D01*
X247638Y-180709D02*
X252362Y-185433D01*
X247638Y-180709D02*
Y-173835D01*
X229709Y-155905D02*
X247638Y-173835D01*
X205906Y-155905D02*
X229709D01*
X203585Y-158226D02*
X205906Y-155905D01*
X186656Y-158226D02*
X203585D01*
X251969Y-187795D02*
X264567D01*
X270706Y-181656D01*
X276932D01*
X280682Y-185406D01*
X286981D01*
X300394Y-198819D01*
X307087D01*
X374222Y-185620D02*
Y-179321D01*
X362598Y-197244D02*
X374222Y-185620D01*
Y-179321D02*
X377038Y-176506D01*
X432002Y-254724D02*
X432283D01*
X422047Y-248425D02*
X429843Y-256221D01*
X430506D01*
X432002Y-254724D01*
X438583Y-247638D02*
X457547D01*
X486489Y-253668D02*
X496063Y-244094D01*
X484520Y-254137D02*
X484989Y-253668D01*
X486489D01*
X484520Y-271475D02*
X485827Y-272781D01*
Y-279429D02*
Y-272781D01*
X484520Y-271475D02*
Y-254137D01*
X427291Y-258787D02*
X462646D01*
X467398Y-254035D02*
X476772D01*
X462646Y-258787D02*
X467398Y-254035D01*
X385541Y-223820D02*
Y-202460D01*
X377559Y-238015D02*
Y-212217D01*
X383572Y-206205D01*
X375359Y-240215D02*
X377559Y-238015D01*
X375359Y-259820D02*
Y-240215D01*
Y-259820D02*
X383200Y-267660D01*
X460967D01*
X464218Y-270911D01*
X474364D01*
X482520Y-262756D01*
Y-251338D01*
X494882Y-238976D01*
X537795D01*
X540945Y-242126D01*
Y-256004D02*
Y-242126D01*
X372047Y-211347D02*
X375698Y-207697D01*
Y-197700D01*
X372047Y-223622D02*
Y-211347D01*
X364961Y-230709D02*
X372047Y-223622D01*
X364961Y-253002D02*
Y-230709D01*
Y-253002D02*
X383218Y-271260D01*
X460630D01*
X472047Y-282677D01*
X488779D01*
X489609Y-281848D01*
Y-257580D01*
X499945Y-247244D01*
X525984D01*
X527854Y-245374D01*
X536614D01*
X416299Y-172441D02*
X421374D01*
X397769Y-153911D02*
X416299Y-172441D01*
X374658Y-153911D02*
X397769D01*
X166070Y-8196D02*
X171536D01*
X163779Y-5906D02*
X166070Y-8196D01*
X149269Y-5906D02*
X163779D01*
X146218Y-8957D02*
X149269Y-5906D01*
X136713Y-8957D02*
X146218D01*
X134055Y-6299D02*
X136713Y-8957D01*
X460270Y-241339D02*
X464472Y-245540D01*
X393701Y-168898D02*
X406693Y-181890D01*
X427521D01*
X463453Y-247883D02*
X465896D01*
X507480Y-293750D02*
Y-289370D01*
Y-298130D02*
Y-293750D01*
X491897Y-296784D02*
X494931Y-293750D01*
X507480D01*
X470031Y-296784D02*
X491897D01*
X469631Y-296385D02*
X470031Y-296784D01*
X463155Y-296385D02*
X469631D01*
X459021Y-292251D02*
X463155Y-296385D01*
X445150Y-292251D02*
X459021D01*
X442126Y-295276D02*
X445150Y-292251D01*
X425984Y-295276D02*
X442126D01*
X415748Y-285039D02*
X425984Y-295276D01*
X348425Y-285039D02*
X415748D01*
X343701Y-280315D02*
X348425Y-285039D01*
X310236Y-280315D02*
X343701D01*
X307073Y-283478D02*
X310236Y-280315D01*
X280414Y-283478D02*
X307073D01*
X493310Y-300987D02*
X495866Y-303543D01*
Y-303543D02*
Y-303543D01*
X464373Y-300987D02*
X493310D01*
X491356Y-308482D02*
X493110Y-310236D01*
X331323Y-256078D02*
X354131Y-233271D01*
X148819Y7480D02*
Y18152D01*
X150477Y19810D01*
X148819Y7480D02*
X150909Y5391D01*
X155633D01*
X162598Y-1575D01*
X141339Y394D02*
X144791Y-3059D01*
X152192D01*
X153677Y-1575D01*
X162598D01*
X179528Y-35433D02*
X188189Y-44094D01*
X164592Y-35433D02*
X179528D01*
X159868Y-30709D02*
X164592Y-35433D01*
X150394Y-30709D02*
X159868D01*
X145718Y-26033D02*
X150394Y-30709D01*
X122539Y-26033D02*
X145718D01*
X188976Y-38976D02*
X212205D01*
X215354Y-42126D01*
X179528Y-29528D02*
X188976Y-38976D01*
X162205Y-29528D02*
X179528D01*
X158710Y-26033D02*
X162205Y-29528D01*
X155328Y-26033D02*
X158710D01*
X208858Y-27756D02*
X220866Y-39764D01*
X180905Y-27756D02*
X208858D01*
X168309Y-15160D02*
X180905Y-27756D01*
X144910Y-15160D02*
X168309D01*
X142348Y-12598D02*
X144910Y-15160D01*
X127165Y-12598D02*
X142348D01*
X497638Y-316629D02*
X507480Y-306787D01*
Y-298130D01*
X535772Y-317771D02*
X540103D01*
X552756Y-305118D01*
X507480Y-289370D02*
X518110Y-278740D01*
Y-255217D01*
X503543Y-334170D02*
X505410Y-336036D01*
X503543Y-334170D02*
Y-318330D01*
X510630Y-311244D01*
Y-294915D01*
X524016Y-281530D01*
Y-257972D01*
X536614Y-245374D01*
X525909Y-305512D02*
X526378Y-305043D01*
Y-265896D01*
X513406Y-302902D02*
X516015Y-305512D01*
X525909D01*
X526378Y-265896D02*
X538976Y-253298D01*
Y-250886D01*
X538189Y-298031D02*
Y-258760D01*
X540945Y-256004D01*
X538189Y-298031D02*
X540209Y-300051D01*
X513386Y-336221D02*
X540209Y-309397D01*
Y-300051D01*
X324476Y-181496D02*
X327658Y-184678D01*
X329528Y-181890D02*
X329681Y-181737D01*
X331308D02*
X331319Y-181726D01*
X329681Y-181737D02*
X331308D01*
X331319Y-181726D02*
X332119D01*
X33587Y-235039D02*
X36220D01*
X25984Y-227437D02*
X33587Y-235039D01*
X25984Y-227437D02*
Y-198881D01*
X321446Y-201388D02*
X324705Y-198130D01*
Y-184678D01*
X300968Y-201388D02*
X321446D01*
X291719Y-192139D02*
X300968Y-201388D01*
X342148Y-192115D02*
X352441D01*
X337774Y-196489D02*
X342148Y-192115D01*
X352441D02*
X354131Y-193804D01*
Y-233271D02*
Y-193804D01*
X109055Y-354331D02*
X159449Y-303937D01*
X12759Y-354331D02*
X109055D01*
X6968Y-348539D02*
X12759Y-354331D01*
X4373Y-348539D02*
X6968D01*
X1575Y-345742D02*
X4373Y-348539D01*
X1575Y-345742D02*
Y-343799D01*
X3672Y-341702D01*
X3968D01*
X12738Y-332931D01*
Y-304077D01*
X5709Y-297047D02*
X12738Y-304077D01*
X35039Y-237402D02*
X54331Y-256693D01*
X133058D01*
X160617Y-229134D01*
X48425Y-261811D02*
X136221D01*
X21582Y-234968D02*
X48425Y-261811D01*
X10007Y-234968D02*
X21582D01*
X10630Y-292126D02*
X19488D01*
X279989Y-238723D02*
X281310Y-237402D01*
X281496D01*
X152362Y-290551D02*
X245290D01*
X4331Y-344488D02*
X19341D01*
X27559Y-337402D02*
X53937Y-311024D01*
X123524D01*
X332119Y-181726D02*
X334252Y-183858D01*
Y-191201D02*
Y-183858D01*
Y-191201D02*
X335827Y-192776D01*
Y-200000D02*
Y-192776D01*
X290551Y-245276D02*
X335827Y-200000D01*
X287008Y-245276D02*
X290551D01*
X283071Y-241339D02*
X287008Y-245276D01*
X341774Y-207439D02*
Y-196326D01*
X328740Y-220472D02*
X341774Y-207439D01*
X323228Y-220472D02*
X328740D01*
X106299Y-351969D02*
X157087Y-301181D01*
X290149Y-240166D02*
X293307Y-237008D01*
X283408Y-237316D02*
Y-212542D01*
Y-237316D02*
X286258Y-240166D01*
X290149D01*
X287008Y-207087D02*
X288583Y-208661D01*
Y-237402D02*
Y-208661D01*
X281598Y-210732D02*
X283408Y-212542D01*
X230962Y-190411D02*
X251283Y-210732D01*
X281598D01*
X30709Y-190411D02*
X230962D01*
X252156Y-207087D02*
X287008D01*
X232829Y-187759D02*
X252156Y-207087D01*
X30422Y-187759D02*
X232829D01*
X28418Y-185755D02*
X30422Y-187759D01*
X9843Y-185755D02*
X28418D01*
X252769Y-192139D02*
X291719D01*
X243701Y-183071D02*
X252769Y-192139D01*
X35755Y-183071D02*
X243701D01*
X33071Y-185755D02*
X35755Y-183071D01*
X323550Y-203937D02*
X331220Y-196266D01*
X254331Y-203937D02*
X323550D01*
X236149Y-185755D02*
X254331Y-203937D01*
X35827Y-185755D02*
X236149D01*
D249*
X619449Y-98189D02*
D03*
Y-108189D02*
D03*
Y-118189D02*
D03*
Y-128189D02*
D03*
D250*
X496620Y-310492D02*
D03*
X245325Y-120837D02*
D03*
X321260Y-166142D02*
D03*
X222351Y-98694D02*
D03*
X245276Y-115748D02*
D03*
X211648Y-103695D02*
D03*
X44001Y-137747D02*
D03*
X71202Y-138095D02*
D03*
X68889Y-137453D02*
D03*
X139370Y-118898D02*
D03*
X317828Y-161260D02*
D03*
X313878Y-161597D02*
D03*
X285827Y-137795D02*
D03*
X284252Y-144095D02*
D03*
X280709Y-137795D02*
D03*
X276083Y-141142D02*
D03*
X140551Y-116535D02*
D03*
X368110Y-330315D02*
D03*
X262006Y-387255D02*
D03*
X365354Y-330315D02*
D03*
X265158Y-387253D02*
D03*
X374114Y-346144D02*
D03*
X246339Y-386975D02*
D03*
X249410Y-387253D02*
D03*
X371359Y-346144D02*
D03*
X360729D02*
D03*
X229331Y-387253D02*
D03*
X357973Y-346144D02*
D03*
X232480Y-387253D02*
D03*
X212795D02*
D03*
X215945D02*
D03*
X356299Y-330315D02*
D03*
X353543D02*
D03*
X284646Y-291732D02*
D03*
X384646Y-184252D02*
D03*
X383083Y-161839D02*
D03*
X421313Y-174784D02*
D03*
X129063Y-136618D02*
D03*
X38613Y-53355D02*
D03*
X172674Y-138386D02*
D03*
X388189Y-162205D02*
D03*
X419798Y-176745D02*
D03*
X126307Y-136224D02*
D03*
X38583Y-58355D02*
D03*
X170311Y-139961D02*
D03*
X491732Y-149213D02*
D03*
X500394Y-145669D02*
D03*
X496063Y-145276D02*
D03*
X491732D02*
D03*
X550391Y-243310D02*
D03*
X477165Y-247244D02*
D03*
X561024Y-183465D02*
D03*
Y-186614D02*
D03*
X35433Y-50787D02*
D03*
X429528Y-231496D02*
D03*
X462205Y-255118D02*
D03*
X324016Y-42913D02*
D03*
X318898Y-43307D02*
D03*
X324016Y-39764D02*
D03*
X318898D02*
D03*
X324016Y-35827D02*
D03*
X318898D02*
D03*
X505118Y-24016D02*
D03*
X500787Y-24409D02*
D03*
X496457Y-24016D02*
D03*
X505118Y-20079D02*
D03*
X500787D02*
D03*
X496457D02*
D03*
X427953Y-206299D02*
D03*
X468504Y-44488D02*
D03*
X463779D02*
D03*
X458661Y-44094D02*
D03*
X468898Y-39764D02*
D03*
X463779Y-39370D02*
D03*
X458661D02*
D03*
X118504Y-40945D02*
D03*
X85039Y-77559D02*
D03*
X426772Y-179528D02*
D03*
X602105Y-99109D02*
D03*
X597244Y-108661D02*
D03*
X592913Y-116535D02*
D03*
X594488Y-132677D02*
D03*
X43701Y-34646D02*
D03*
X51287Y-126878D02*
D03*
X13386D02*
D03*
X29543Y-345214D02*
D03*
X240158Y-278740D02*
D03*
X35433Y15354D02*
D03*
X36220Y8268D02*
D03*
X35827Y1575D02*
D03*
X298819Y-269685D02*
D03*
X399213Y-193307D02*
D03*
X432283Y-254724D02*
D03*
X496063Y-244094D02*
D03*
X462992Y-76378D02*
D03*
X153150Y-113386D02*
D03*
X591339Y-144488D02*
D03*
X582165Y-163898D02*
D03*
X329528Y-181890D02*
D03*
X307087Y-198819D02*
D03*
X279134Y-230315D02*
D03*
X280315Y-226378D02*
D03*
X277165Y-236221D02*
D03*
X281496Y-237402D02*
D03*
X27559Y-337402D02*
D03*
X288583Y-237402D02*
D03*
X293307Y-237008D02*
D03*
X407874Y-216535D02*
D03*
X408760Y-238189D02*
D03*
X140116Y-124048D02*
D03*
X141339Y394D02*
D03*
X177559Y-87795D02*
D03*
X169291Y13386D02*
D03*
X162598Y-1575D02*
D03*
X151181Y18110D02*
D03*
X134055Y-6299D02*
D03*
X485827Y-279429D02*
D03*
X476772Y-254035D02*
D03*
X495866Y-303543D02*
D03*
X493110Y-310236D02*
D03*
X127165Y-12598D02*
D03*
X507480Y-298130D02*
D03*
X540945Y-256004D02*
D03*
X538976Y-250886D02*
D03*
X536614Y-245374D02*
D03*
X518110Y-255217D02*
D03*
X220866Y-39764D02*
D03*
X215354Y-42126D02*
D03*
X210236Y-44094D02*
D03*
X101181Y-38583D02*
D03*
X149606Y-80315D02*
D03*
X121467Y-74575D02*
D03*
X552756Y-305118D02*
D03*
X513406Y-302902D02*
D03*
X513386Y-336221D02*
D03*
X505410Y-336036D02*
D03*
X616142Y-47638D02*
D03*
X618898Y-50787D02*
D03*
X613386D02*
D03*
X609547Y-51181D02*
D03*
X606693Y-50787D02*
D03*
X601575Y-53543D02*
D03*
X599213Y-50000D02*
D03*
X223209Y-137815D02*
D03*
X130245Y-120870D02*
D03*
X153150Y-99691D02*
D03*
X168110Y-100132D02*
D03*
X178185Y-133661D02*
D03*
X164843Y-114040D02*
D03*
X66102Y-64085D02*
D03*
X86614Y-56299D02*
D03*
Y-39370D02*
D03*
X88583Y-53937D02*
D03*
X85039D02*
D03*
X88583Y-50787D02*
D03*
X85039D02*
D03*
X88583Y-46457D02*
D03*
X85039Y-46850D02*
D03*
X388713Y-128731D02*
D03*
X369685Y-123622D02*
D03*
Y-120866D02*
D03*
Y-118110D02*
D03*
X366929Y-123622D02*
D03*
Y-120866D02*
D03*
X363779Y-123622D02*
D03*
X366929Y-118110D02*
D03*
X363779Y-120866D02*
D03*
Y-118110D02*
D03*
X445669Y-128347D02*
D03*
X449606D02*
D03*
Y-124803D02*
D03*
Y-121653D02*
D03*
X325776Y-293701D02*
D03*
X345161Y-292913D02*
D03*
X368232Y-217717D02*
D03*
X390158D02*
D03*
X393701Y-168898D02*
D03*
X310236Y-165748D02*
D03*
X375698Y-197700D02*
D03*
X383572Y-206205D02*
D03*
X385541Y-202460D02*
D03*
X155328Y-26033D02*
D03*
X122539D02*
D03*
X26772Y-348819D02*
D03*
X4331Y-344488D02*
D03*
X35039Y-289961D02*
D03*
Y-285827D02*
D03*
X27067Y-298727D02*
D03*
X10630Y-292126D02*
D03*
X10007Y-234968D02*
D03*
X36220Y-235039D02*
D03*
X36614Y-232677D02*
D03*
X35039Y-237402D02*
D03*
X30709Y-190411D02*
D03*
X33071Y-185755D02*
D03*
X35827D02*
D03*
X9843D02*
D03*
X245965Y-264497D02*
D03*
Y-254655D02*
D03*
X432835Y-291755D02*
D03*
X472047Y-221260D02*
D03*
X430020Y-218979D02*
D03*
X472047Y-223228D02*
D03*
X430020Y-220948D02*
D03*
Y-222916D02*
D03*
X472047Y-219291D02*
D03*
X430020Y-217010D02*
D03*
X337774Y-196489D02*
D03*
X274719Y-244928D02*
D03*
X276755Y-246539D02*
D03*
X280414Y-283478D02*
D03*
Y-287478D02*
D03*
X331220Y-196266D02*
D03*
X341774Y-196326D02*
D03*
X326705Y-179059D02*
D03*
X324705Y-184678D02*
D03*
X463453Y-247883D02*
D03*
X464472Y-245540D02*
D03*
X327658Y-184678D02*
D03*
X244028Y-262466D02*
D03*
Y-258497D02*
D03*
X243996Y-252592D02*
D03*
X245965Y-250655D02*
D03*
X243996Y-248655D02*
D03*
X245965Y-260497D02*
D03*
X472047Y-217323D02*
D03*
X362598Y-197244D02*
D03*
X432579Y-283251D02*
D03*
Y-286400D02*
D03*
X432720Y-289358D02*
D03*
D252*
X378855Y-355509D02*
D03*
X219818Y-382320D02*
D03*
M02*
